G04 ================== begin FILE IDENTIFICATION RECORD ==================*
G04 Layout Name:  9049_F0T_FAN_BOARD_MP5048_D_v02_20221209_0830.brd*
G04 Film Name:    smt.art*
G04 File Format:  Gerber RS274X*
G04 File Origin:  Cadence Allegro 17.2-S081*
G04 Origin Date:  Mon Dec 12 15:05:04 2022*
G04 *
G04 Layer:  DRAWING FORMAT/TITLE_BLOCK_A*
G04 Layer:  DRAWING FORMAT/TITLE_BLOCK*
G04 Layer:  VIA CLASS/SOLDERMASK_TOP*
G04 Layer:  PIN/SOLDERMASK_TOP*
G04 Layer:  PACKAGE GEOMETRY/SOLDERMASK_TOP*
G04 Layer:  MANUFACTURING/PHOTOPLOT_OUTLINE*
G04 Layer:  DRAWING FORMAT/TITLE_DATA_SMT*
G04 Layer:  BOARD GEOMETRY/SOLDERMASK_TOP*
G04 *
G04 Offset:    (0.00 0.00)*
G04 Mirror:    No*
G04 Mode:      Positive*
G04 Rotation:  0*
G04 FullContactRelief:  No*
G04 UndefLineWidth:     6.00*
G04 ================== end FILE IDENTIFICATION RECORD ====================*
%FSLAX25Y25*MOIN*%
%IR0*IPPOS*OFA0.00000B0.00000*MIA0B0*SFA1.00000B1.00000*%
%ADD46R,.036X.201*%
%ADD12C,.034*%
%ADD20R,.178X.091*%
%ADD17C,.058*%
%ADD10C,.085*%
%ADD16C,.079*%
%ADD18R,.058X.058*%
%AMMACRO25*
4,1,28,-.00589,-.01192,
-.006913,-.011842,
-.007907,-.011587,
-.008842,-.011163,
-.009688,-.010584,
-.010422,-.009866,
-.011019,-.009032,
-.011463,-.008107,
-.011739,-.007119,
-.01184,-.006097,
-.01184,-.00603,
-.01184,.00148,
-.00948,.00148,
-.00948,.01191,
.00948,.01191,
.00948,.00148,
.01184,.00148,
.01184,-.00603,
.011751,-.007052,
.011486,-.008044,
.011053,-.008974,
.010465,-.009815,
.00974,-.010541,
.0089,-.01113,
.00797,-.011564,
.006979,-.01183,
.005957,-.01192,
.00589,-.01192,
-.00589,-.01192,
0.0*
%
%ADD25MACRO25*%
%AMMACRO15*
4,1,28,-.01192,.00589,
-.011842,.006913,
-.011587,.007907,
-.011163,.008842,
-.010584,.009688,
-.009866,.010422,
-.009032,.011019,
-.008107,.011463,
-.007119,.011739,
-.006097,.01184,
-.00603,.01184,
.00148,.01184,
.00148,.00948,
.01191,.00948,
.01191,-.00948,
.00148,-.00948,
.00148,-.01184,
-.00603,-.01184,
-.007052,-.011751,
-.008044,-.011486,
-.008974,-.011053,
-.009815,-.010465,
-.010541,-.00974,
-.01113,-.0089,
-.011564,-.00797,
-.01183,-.006979,
-.01192,-.005957,
-.01192,-.00589,
-.01192,.00589,
0.0*
%
%ADD15MACRO15*%
%AMMACRO24*
4,1,28,.0059,.01191,
.006923,.01183,
.007916,.011573,
.00885,.011148,
.009696,.010567,
.010428,.009849,
.011024,.009013,
.011466,.008088,
.011741,.007099,
.01184,.006078,
.01184,.00602,
.01184,-.00149,
.00948,-.00149,
.00948,-.01192,
-.00948,-.01192,
-.00948,-.00149,
-.01184,-.00149,
-.01184,.00602,
-.011751,.007042,
-.011486,.008033,
-.011053,.008964,
-.010465,.009805,
-.00974,.010531,
-.0089,.01112,
-.007971,.011554,
-.00698,.01182,
-.005958,.01191,
-.0059,.01191,
.0059,.01191,
0.0*
%
%ADD24MACRO24*%
%AMMACRO23*
4,1,28,.01191,-.0059,
.01183,-.006923,
.011573,-.007916,
.011148,-.00885,
.010567,-.009696,
.009849,-.010428,
.009013,-.011024,
.008088,-.011466,
.007099,-.011741,
.006078,-.01184,
.00602,-.01184,
-.00149,-.01184,
-.00149,-.00948,
-.01192,-.00948,
-.01192,.00948,
-.00149,.00948,
-.00149,.01184,
.00602,.01184,
.007042,.011751,
.008033,.011486,
.008964,.011053,
.009805,.010465,
.010531,.00974,
.01112,.0089,
.011554,.007971,
.01182,.00698,
.01191,.005958,
.01191,.0059,
.01191,-.0059,
0.0*
%
%ADD23MACRO23*%
%ADD40R,.024X.02*%
%ADD48R,.02X.024*%
%ADD47R,.04X.032*%
%ADD27R,.04X.015*%
%ADD13R,.024X.022*%
%ADD44R,.036X.011*%
%ADD26R,.015X.04*%
%ADD11R,.022X.024*%
%ADD42R,.011X.036*%
%ADD41R,.036X.032*%
%ADD39R,.032X.036*%
%ADD51C,.404*%
%ADD33R,.072X.026*%
%ADD19R,.054X.044*%
%ADD45R,.028X.026*%
%ADD32R,.063X.018*%
%ADD14R,.044X.054*%
%ADD50R,.018X.063*%
%ADD49C,.118*%
%ADD43R,.111X.111*%
%ADD38R,.036X.028*%
%ADD37R,.026X.028*%
%ADD35C,.145*%
%ADD52R,.177X.252*%
%ADD34R,.028X.036*%
%ADD36R,.036X.038*%
%ADD28R,.113X.113*%
%ADD31O,.359X.831*%
%AMMACRO30*
4,1,28,.00589,.01192,
.006913,.011842,
.007907,.011587,
.008842,.011163,
.009688,.010584,
.010422,.009866,
.011019,.009032,
.011463,.008107,
.011739,.007119,
.01184,.006097,
.01184,.00603,
.01184,-.00148,
.00948,-.00148,
.00948,-.01191,
-.00948,-.01191,
-.00948,-.00148,
-.01184,-.00148,
-.01184,.00603,
-.011751,.007052,
-.011486,.008044,
-.011053,.008974,
-.010465,.009815,
-.00974,.010541,
-.0089,.01113,
-.00797,.011564,
-.006979,.01183,
-.005957,.01192,
-.00589,.01192,
.00589,.01192,
0.0*
%
%ADD30MACRO30*%
%AMMACRO22*
4,1,28,.01192,-.00589,
.011842,-.006913,
.011587,-.007907,
.011163,-.008842,
.010584,-.009688,
.009866,-.010422,
.009032,-.011019,
.008107,-.011463,
.007119,-.011739,
.006097,-.01184,
.00603,-.01184,
-.00148,-.01184,
-.00148,-.00948,
-.01191,-.00948,
-.01191,.00948,
-.00148,.00948,
-.00148,.01184,
.00603,.01184,
.007052,.011751,
.008044,.011486,
.008974,.011053,
.009815,.010465,
.010541,.00974,
.01113,.0089,
.011564,.00797,
.01183,.006979,
.01192,.005957,
.01192,.00589,
.01192,-.00589,
0.0*
%
%ADD22MACRO22*%
%AMMACRO29*
4,1,28,-.0059,-.01191,
-.006923,-.01183,
-.007916,-.011573,
-.00885,-.011148,
-.009696,-.010567,
-.010428,-.009849,
-.011024,-.009013,
-.011466,-.008088,
-.011741,-.007099,
-.01184,-.006078,
-.01184,-.00602,
-.01184,.00149,
-.00948,.00149,
-.00948,.01192,
.00948,.01192,
.00948,.00149,
.01184,.00149,
.01184,-.00602,
.011751,-.007042,
.011486,-.008033,
.011053,-.008964,
.010465,-.009805,
.00974,-.010531,
.0089,-.01112,
.007971,-.011554,
.00698,-.01182,
.005958,-.01191,
.0059,-.01191,
-.0059,-.01191,
0.0*
%
%ADD29MACRO29*%
%AMMACRO21*
4,1,28,-.01191,.0059,
-.01183,.006923,
-.011573,.007916,
-.011148,.00885,
-.010567,.009696,
-.009849,.010428,
-.009013,.011024,
-.008088,.011466,
-.007099,.011741,
-.006078,.01184,
-.00602,.01184,
.00149,.01184,
.00149,.00948,
.01192,.00948,
.01192,-.00948,
.00149,-.00948,
.00149,-.01184,
-.00602,-.01184,
-.007042,-.011751,
-.008033,-.011486,
-.008964,-.011053,
-.009805,-.010465,
-.010531,-.00974,
-.01112,-.0089,
-.011554,-.007971,
-.01182,-.00698,
-.01191,-.005958,
-.01191,-.0059,
-.01191,.0059,
0.0*
%
%ADD21MACRO21*%
%ADD53C,.02*%
%ADD54C,.006*%
G75*
%LPD*%
G75*
G36*
G01X105394Y27176D02*
Y7283D01*
X99489Y1378D01*
X80158D01*
X74252Y7283D01*
Y27176D01*
X105394D01*
G37*
G36*
G01X101400Y388000D02*
G03I-5900J0D01*
G37*
G36*
G01X123386Y1378D02*
X129292Y7283D01*
Y32285D01*
X107922D01*
Y7085D01*
X108348D01*
X114055Y1378D01*
X123386D01*
G37*
G36*
G01X163900Y17500D02*
G03I-5900J0D01*
G37*
G36*
G01X172860Y1304230D02*
G03I-5900J0D01*
G37*
G54D10*
X-58431Y824000D03*
X-63431Y837184D03*
Y1152816D03*
X-58431Y1166000D03*
X-53431Y837184D03*
Y1152816D03*
X-27318Y824000D03*
X-32318Y837184D03*
X-22318D03*
X-32318Y1152816D03*
X-22318D03*
X-27318Y1166000D03*
G54D11*
X9425Y124000D03*
X12575D03*
X25075D03*
X21925D03*
X16575Y393000D03*
X13425D03*
X15075Y487000D03*
X11925D03*
X27575D03*
X24425D03*
X11925Y491000D03*
X15075D03*
X17075Y1215000D03*
X13925D03*
X53775Y500500D03*
Y495500D03*
Y490500D03*
Y485500D03*
X53850Y480500D03*
X53775Y526000D03*
Y521000D03*
Y516000D03*
Y511000D03*
Y506000D03*
X53850Y536000D03*
X53775Y531000D03*
X54925Y805000D03*
Y816000D03*
Y1168500D03*
Y1156000D03*
Y1160000D03*
Y1178500D03*
X36075Y1235500D03*
X32925D03*
X65425Y81000D03*
X68575D03*
X65425Y98000D03*
X68575D03*
X75075Y406000D03*
X71925D03*
X64925Y427000D03*
X68075D03*
X64925Y443500D03*
X68075D03*
X58425Y475000D03*
X61575D03*
X60075Y500500D03*
X56925D03*
X60075Y495500D03*
X56925D03*
X60075Y490500D03*
X56925D03*
X60075Y485500D03*
X56925D03*
X60150Y480500D03*
X57000D03*
X56925Y500500D03*
Y495500D03*
Y490500D03*
Y485500D03*
X57000Y480500D03*
X60075Y526000D03*
X56925D03*
X60075Y521000D03*
X56925D03*
X60075Y516000D03*
X56925D03*
X60075Y511000D03*
X56925D03*
X60075Y506000D03*
X56925D03*
Y526000D03*
Y521000D03*
Y516000D03*
Y511000D03*
Y506000D03*
X60150Y536000D03*
X57000D03*
X60075Y531000D03*
X56925D03*
X57000Y536000D03*
X56925Y531000D03*
X74075Y746500D03*
X70925D03*
X58075Y805000D03*
Y816000D03*
X71425Y823500D03*
X74575D03*
X64925Y807500D03*
X68075D03*
X66925Y834000D03*
X70075D03*
X75075Y1138500D03*
X71925D03*
X58075Y1168500D03*
Y1156000D03*
Y1160000D03*
X64425Y1168000D03*
X67575D03*
X58075Y1178500D03*
X64425Y1184000D03*
X67575D03*
X72575Y1196500D03*
X69425D03*
X98925Y527000D03*
X120425Y144500D03*
X123575D03*
X124425Y429000D03*
X102075Y527000D03*
X129925Y65000D03*
X133075D03*
X138575Y81000D03*
X135425D03*
X138575Y97000D03*
X135425D03*
X127925Y114000D03*
X131075D03*
X129425Y403728D03*
X132575D03*
X127575Y429000D03*
X139575Y424500D03*
X136425D03*
X128425Y465500D03*
X131575D03*
X147350Y487000D03*
X147425Y492000D03*
Y497000D03*
Y502000D03*
Y507000D03*
Y512000D03*
Y517000D03*
Y522000D03*
Y527000D03*
Y532000D03*
Y537000D03*
X147350Y542000D03*
X128425Y762000D03*
X131575D03*
X148075Y796500D03*
X144925D03*
X148075Y786500D03*
X144925D03*
X139075Y790800D03*
X135925D03*
X128425Y824614D03*
X131575D03*
X145425Y1146400D03*
Y1156000D03*
Y1165000D03*
Y1169500D03*
X139075Y1170000D03*
X135925D03*
X139075Y1154000D03*
X135925D03*
X128425Y1188000D03*
X131575D03*
X150500Y487000D03*
X150575Y492000D03*
Y497000D03*
Y502000D03*
X153650Y487000D03*
X150500D03*
X153725Y492000D03*
X150575D03*
X153725Y497000D03*
X150575D03*
X153725Y502000D03*
X150575D03*
Y507000D03*
Y512000D03*
Y517000D03*
Y522000D03*
X153725Y507000D03*
X150575D03*
X153725Y512000D03*
X150575D03*
X153725Y517000D03*
X150575D03*
X153725Y522000D03*
X150575D03*
Y527000D03*
Y532000D03*
Y537000D03*
X150500Y542000D03*
X153725Y527000D03*
X150575D03*
X153725Y532000D03*
X150575D03*
X153725Y537000D03*
X150575D03*
X153650Y542000D03*
X150500D03*
X148575Y1146400D03*
Y1156000D03*
Y1165000D03*
Y1169500D03*
X190425Y124500D03*
X193575D03*
X177925D03*
X181075D03*
X186925Y490000D03*
X190075D03*
X186425Y1215000D03*
X189575D03*
X178075Y1236500D03*
X174925D03*
G54D20*
X22780Y155131D03*
X27480Y880000D03*
X57820Y155131D03*
X46023Y358300D03*
X62520Y880000D03*
X46023Y1085072D03*
X81063Y358300D03*
Y1085072D03*
X121380Y358100D03*
X119980Y1085072D03*
X145634Y155131D03*
X141880Y883400D03*
X155020Y1085072D03*
X156420Y358100D03*
X176920Y883400D03*
X180674Y155131D03*
G54D21*
X26516Y255500D03*
X19307Y262728D03*
X22516Y251500D03*
X15016Y641000D03*
Y660000D03*
Y654000D03*
Y645500D03*
Y686000D03*
Y680500D03*
Y672500D03*
Y666500D03*
X13516Y715000D03*
Y727000D03*
X20016Y974500D03*
X14016Y1239500D03*
X54559Y56342D03*
X55016Y79692D03*
X32807Y263728D03*
X43577Y277728D03*
X49516Y289000D03*
X54559Y401378D03*
X55016Y424728D03*
X51016Y641000D03*
Y660000D03*
Y654000D03*
Y647000D03*
Y685000D03*
Y679000D03*
Y672500D03*
Y666500D03*
X34516Y727500D03*
X54559Y764764D03*
X55016Y788114D03*
X44077Y1004500D03*
X32807Y990500D03*
X54559Y1128650D03*
X55016Y1152000D03*
X69016Y641000D03*
Y657500D03*
Y651500D03*
Y647000D03*
Y685000D03*
Y679000D03*
Y672500D03*
Y666500D03*
X71016Y704000D03*
Y709500D03*
Y719000D03*
Y724000D03*
Y715000D03*
Y742500D03*
Y751500D03*
X63516Y778500D03*
X56516Y1024000D03*
Y1016000D03*
X88516Y92000D03*
X99016Y478500D03*
Y483425D03*
Y498500D03*
Y488500D03*
Y517500D03*
X80516Y676000D03*
Y684000D03*
Y692000D03*
Y700000D03*
X99016Y706500D03*
Y711000D03*
X95516Y731000D03*
Y738000D03*
Y745000D03*
X104600Y81551D03*
X112516Y667500D03*
Y671500D03*
Y675500D03*
Y679500D03*
Y683500D03*
Y687500D03*
X106516Y706500D03*
Y711000D03*
X112516Y693000D03*
X106516Y731000D03*
Y718000D03*
Y738000D03*
Y745000D03*
X118016Y752000D03*
X145516Y107842D03*
Y98842D03*
X137016Y107842D03*
X138516Y126842D03*
X128016Y118000D03*
X143016Y253000D03*
X142998Y262728D03*
X129516Y408000D03*
X145516Y442728D03*
Y451728D03*
X128516Y456728D03*
X137016Y451728D03*
X137516Y470728D03*
X129516Y728500D03*
X145516Y806114D03*
Y815114D03*
X128516Y820114D03*
X137016Y815114D03*
X137516Y834114D03*
X146016Y985000D03*
X142998Y992649D03*
X145516Y1160500D03*
Y1178500D03*
X128516Y1183500D03*
X137516Y1197500D03*
X156498Y263728D03*
X152874Y277728D03*
X159016Y288000D03*
X170016Y663500D03*
Y659500D03*
Y651500D03*
X164016Y706000D03*
Y733000D03*
X149016Y729000D03*
X152874Y1004500D03*
X156498Y993649D03*
X165016Y1025500D03*
Y1017500D03*
X188516Y515500D03*
Y521000D03*
Y532000D03*
Y526500D03*
X176016Y720000D03*
Y713000D03*
Y747000D03*
Y740000D03*
X186516Y1240500D03*
G54D30*
X27000Y533983D03*
X19000D03*
X23000D03*
X17000Y992483D03*
X33000Y533983D03*
X64543Y57825D03*
X77000Y107483D03*
Y89983D03*
X66561Y282211D03*
X77000Y452983D03*
Y435483D03*
X71000Y536983D03*
X76500D03*
Y528983D03*
X68000Y567983D03*
X75000D03*
X78500Y611483D03*
X72000Y631483D03*
X68000D03*
X77000Y803483D03*
Y816483D03*
X67061Y1008983D03*
X76500Y1160483D03*
Y1176483D03*
X96000Y56183D03*
X91500D03*
Y112483D03*
Y470483D03*
X93000Y536983D03*
X87500D03*
X82000D03*
Y528983D03*
X101000Y558983D03*
X91000D03*
X95500D03*
X80000D03*
X93000Y567983D03*
X101000D03*
X85000D03*
X80900Y631483D03*
X80800Y642983D03*
X91500Y833483D03*
Y1196483D03*
X106500Y56183D03*
X102500D03*
X103000Y132983D03*
X113500Y403483D03*
X115000Y423483D03*
X113500Y490483D03*
X119000D03*
X106500Y503483D03*
X106000Y534483D03*
X110000D03*
X116000Y526983D03*
X114500Y558983D03*
X124500Y557983D03*
X107500Y558983D03*
X124500Y567983D03*
X107500D03*
X117000D03*
X117500Y768483D03*
X114500Y788483D03*
X118500Y1131483D03*
X115500Y1151483D03*
X143500Y57983D03*
X135500Y490483D03*
X131500Y557983D03*
X135500D03*
Y567983D03*
X131500D03*
X129000Y1131983D03*
X166500Y534983D03*
Y541983D03*
X161000Y857483D03*
X175858Y282211D03*
X171500Y534983D03*
Y541983D03*
X176500Y534983D03*
X175858Y1008983D03*
G54D12*
X9425Y129000D03*
X9400Y241516D03*
X10500Y274500D03*
X11800Y284000D03*
X11433Y983048D03*
X17200Y124000D03*
X25075Y119000D03*
X34544Y192540D03*
X34480Y202243D03*
X29191Y210428D03*
X22170Y246150D03*
X14791Y247715D03*
X29390Y246960D03*
X16873Y257024D03*
X27987Y264636D03*
X21500Y267500D03*
X32716Y273500D03*
X24000Y276000D03*
X18185Y312228D03*
X27185D03*
X17500Y361728D03*
X26500D03*
X29820Y379910D03*
X24880Y480480D03*
X19700Y487000D03*
X21320Y506500D03*
X16580Y526220D03*
X22100Y526120D03*
X21070Y636050D03*
X19850Y691868D03*
X21500Y727000D03*
X22000Y718000D03*
X29000Y728000D03*
X19820Y754600D03*
X27587Y937815D03*
X14791Y976000D03*
X27886Y972134D03*
X23009Y995491D03*
X30522Y1000288D03*
X18185Y1038900D03*
X25000Y1104300D03*
X25060Y1215540D03*
X50000Y63842D03*
X48100Y56342D03*
X48184Y73876D03*
X48313Y68687D03*
X49985Y81177D03*
X49500Y109600D03*
X50000Y97500D03*
X51400Y120342D03*
X36880Y249217D03*
X42309Y251270D03*
X48456Y230214D03*
X41864Y265636D03*
X44500Y272767D03*
X40500Y295500D03*
X51956Y283826D03*
X45500Y298350D03*
X52000Y298528D03*
X57430Y298520D03*
X49800Y401378D03*
X46500Y416000D03*
Y423868D03*
Y432116D03*
X50000Y428000D03*
X49200Y457228D03*
X46500Y451614D03*
Y463378D03*
X48217Y480500D03*
X41196Y489754D03*
X49023Y490500D03*
X45953Y495500D03*
X48872Y500500D03*
X44140Y505060D03*
X48970Y507700D03*
X47140Y512860D03*
X48500Y519850D03*
X49120Y526000D03*
X43450Y528170D03*
X47865Y534580D03*
X54160Y689760D03*
X49400Y772264D03*
X49800Y764764D03*
X47100Y789700D03*
X46500Y783764D03*
X46900Y795128D03*
X48000Y801075D03*
X50900Y826998D03*
X46500Y820614D03*
X46900Y806500D03*
X35259Y968798D03*
X38500Y977199D03*
X40500Y995000D03*
X39061Y1005000D03*
X51852Y1012249D03*
X42000Y1023000D03*
X44100Y1027850D03*
X50000Y1023000D03*
X46500Y1147650D03*
X53900Y1142766D03*
X46409Y1136709D03*
X49400Y1153000D03*
X49764Y1175063D03*
X47000Y1166500D03*
X48200Y1160000D03*
X50900Y1190150D03*
X46500Y1184000D03*
X37200Y1215500D03*
X40700Y1235600D03*
X73877Y80768D03*
X81400Y95000D03*
X67310Y114250D03*
X71689Y302000D03*
X64561Y298446D03*
X76682Y426000D03*
X80650Y457650D03*
X65300Y480500D03*
X68930Y485500D03*
X65300Y490500D03*
X70460Y495120D03*
X64700Y498190D03*
X69290Y500790D03*
X65479Y504809D03*
X64800Y510030D03*
X66290Y515220D03*
X64820Y520300D03*
X64710Y525630D03*
X73500Y521000D03*
X64945Y534505D03*
X61710Y559000D03*
X79930Y579000D03*
X72899Y582500D03*
X80400Y621200D03*
X73285Y616764D03*
X64480Y636220D03*
X72000Y623700D03*
X60500Y693500D03*
X65610Y700000D03*
X60260Y704661D03*
X65920Y708260D03*
X65100Y725200D03*
X65870Y715000D03*
X65087Y747089D03*
X80500Y822500D03*
X72000Y1013500D03*
X74000Y1026000D03*
X66000Y1025000D03*
X64231Y1115268D03*
X80000Y1151500D03*
X79991Y1181260D03*
X93075Y72000D03*
X93312Y132925D03*
X89169Y401350D03*
X93648Y482621D03*
X93477Y490571D03*
X90990Y521240D03*
X92194Y572807D03*
X81442Y573302D03*
X89610Y580015D03*
X99500Y578500D03*
X87977Y623045D03*
X95732Y622114D03*
X101284Y671500D03*
X101124Y715876D03*
X95980Y805970D03*
X81500Y789000D03*
X95920Y813575D03*
X102500Y979500D03*
X82000Y1123500D03*
X97760Y1193780D03*
X112500Y65500D03*
X110425Y114000D03*
X124000Y150630D03*
X115680Y139670D03*
X127482Y312228D03*
X118500Y403500D03*
X110000Y392500D03*
X122100Y418100D03*
X127000Y446000D03*
X122500Y473500D03*
X122070Y495240D03*
X114913Y495488D03*
X106740Y508780D03*
X110000Y526490D03*
X107320Y519640D03*
X109000Y573500D03*
X123603Y575972D03*
X107000Y621000D03*
X115500Y622000D03*
X124323Y621748D03*
X123608Y664209D03*
X124830Y679870D03*
X120400Y670820D03*
X124820Y674220D03*
X120305Y677055D03*
X120550Y689650D03*
X121920Y684380D03*
X112339Y701350D03*
X119975Y723132D03*
X121500Y809000D03*
X122000Y838500D03*
X127182Y1039000D03*
X120300Y1148500D03*
X123000Y1173500D03*
X116737Y1162763D03*
X112281Y1194600D03*
X138700Y57700D03*
X135700Y102300D03*
X128000Y251000D03*
X137495Y248875D03*
X142400Y269800D03*
X133963Y255892D03*
X129370Y495230D03*
X141500Y487500D03*
X136000Y498500D03*
X141390Y496350D03*
X142060Y522960D03*
X133470Y527000D03*
X139020Y514480D03*
X136560Y519360D03*
X135420Y537000D03*
X139890Y542000D03*
X142330Y532000D03*
X131875Y623376D03*
X139350Y694910D03*
X129112Y978769D03*
X136505Y986470D03*
X138605Y977649D03*
X146644Y1007363D03*
X149500Y1023000D03*
X157000Y52982D03*
X156950Y76050D03*
X156782Y87719D03*
X157000Y101000D03*
X153200Y107842D03*
X157000Y93000D03*
X154124Y124576D03*
X156600Y114600D03*
X165164Y189143D03*
X164964Y199543D03*
X164864Y208443D03*
X152500Y249501D03*
X161200Y251200D03*
X159430Y244830D03*
X161128Y283003D03*
X152420Y296500D03*
X167000Y296310D03*
X160777Y275688D03*
X160000Y298500D03*
X154500Y410000D03*
X157496Y400176D03*
X155598Y426934D03*
X155309Y435073D03*
X155686Y418730D03*
X153324Y449248D03*
X157000Y455738D03*
Y442728D03*
Y468500D03*
X152600Y463612D03*
X162220Y505480D03*
X166630Y502000D03*
X159680Y497000D03*
X165300Y492000D03*
X159830Y487000D03*
X158870Y525510D03*
X158410Y516230D03*
X158570Y509929D03*
X159730Y539520D03*
X158790Y533400D03*
X164152Y657373D03*
X165103Y678233D03*
X164572Y669102D03*
X165032Y685986D03*
X161312Y696884D03*
X171087Y724838D03*
X172000Y751500D03*
X173800Y759446D03*
X152266Y773430D03*
X155800Y779425D03*
X156500Y787700D03*
X157000Y801500D03*
X154168Y812669D03*
X155800Y826998D03*
X157000Y819114D03*
X153300Y806114D03*
X156900Y834114D03*
X154502Y971101D03*
X152823Y978573D03*
X160732Y977966D03*
X164337Y1002475D03*
X159500Y1023000D03*
X153150Y1028430D03*
X152600Y1135000D03*
X157000Y1146925D03*
Y1155000D03*
Y1164500D03*
X153200Y1169500D03*
X157000Y1182500D03*
X157500Y1197500D03*
X152600Y1190384D03*
X155286Y1175985D03*
X162800Y1215277D03*
X162400Y1229900D03*
X193575Y129925D03*
X185700Y124500D03*
Y112900D03*
X185358Y230328D03*
X173858Y298500D03*
X183500Y299500D03*
X188800Y408300D03*
X183610Y398050D03*
X185700Y476200D03*
X194000Y550000D03*
X182730Y535090D03*
X183720Y529289D03*
X176350Y540120D03*
X187500Y643500D03*
X180500Y684500D03*
X179000Y676500D03*
X187925Y701000D03*
X181000Y696500D03*
X184425Y738000D03*
X193308Y839608D03*
X177021Y1016322D03*
X182058Y1022519D03*
X173858Y1025500D03*
G54D22*
X29483Y255500D03*
X22274Y262728D03*
X25483Y251500D03*
X17983Y641000D03*
Y660000D03*
Y654000D03*
Y645500D03*
Y686000D03*
Y680500D03*
Y672500D03*
Y666500D03*
X16483Y715000D03*
Y727000D03*
X22983Y974500D03*
X16983Y1239500D03*
X35774Y263728D03*
X46544Y277728D03*
X52483Y289000D03*
X53983Y641000D03*
Y660000D03*
Y654000D03*
Y647000D03*
Y685000D03*
Y679000D03*
Y672500D03*
Y666500D03*
X37483Y727500D03*
X47044Y1004500D03*
X35774Y990500D03*
X57526Y56342D03*
X57983Y79692D03*
X57526Y401378D03*
X57983Y424728D03*
X71983Y641000D03*
Y657500D03*
Y651500D03*
Y647000D03*
Y685000D03*
Y679000D03*
Y672500D03*
Y666500D03*
X73983Y704000D03*
Y709500D03*
Y719000D03*
Y724000D03*
Y715000D03*
Y742500D03*
Y751500D03*
X57526Y764764D03*
X66483Y778500D03*
X57983Y788114D03*
X59483Y1024000D03*
Y1016000D03*
X57526Y1128650D03*
X57983Y1152000D03*
X91483Y92000D03*
X83483Y676000D03*
Y684000D03*
Y692000D03*
Y700000D03*
X98483Y731000D03*
Y738000D03*
Y745000D03*
X107567Y81551D03*
X101983Y478500D03*
Y483425D03*
Y498500D03*
Y488500D03*
Y517500D03*
X115483Y667500D03*
Y671500D03*
Y675500D03*
Y679500D03*
Y683500D03*
Y687500D03*
X109483Y706500D03*
Y711000D03*
X115483Y693000D03*
X101983Y706500D03*
Y711000D03*
X109483Y731000D03*
Y718000D03*
Y738000D03*
Y745000D03*
X120983Y752000D03*
X139983Y107842D03*
X141483Y126842D03*
X130983Y118000D03*
X145983Y253000D03*
X145965Y262728D03*
X132483Y408000D03*
X131483Y456728D03*
X139983Y451728D03*
X140483Y470728D03*
X132483Y728500D03*
X131483Y820114D03*
X139983Y815114D03*
X140483Y834114D03*
X145965Y992649D03*
X131483Y1183500D03*
X140483Y1197500D03*
X148483Y107842D03*
Y98842D03*
X159465Y263728D03*
X155841Y277728D03*
X161983Y288000D03*
X148483Y442728D03*
Y451728D03*
X166983Y706000D03*
Y733000D03*
X151983Y729000D03*
X148483Y806114D03*
Y815114D03*
X148983Y985000D03*
X155841Y1004500D03*
X159465Y993649D03*
X167983Y1025500D03*
Y1017500D03*
X148483Y1160500D03*
Y1178500D03*
X191483Y515500D03*
Y521000D03*
Y532000D03*
Y526500D03*
X172983Y663500D03*
Y659500D03*
Y651500D03*
X178983Y720000D03*
Y713000D03*
Y747000D03*
Y740000D03*
X189483Y1240500D03*
G54D31*
X42717Y597091D03*
X101772Y180748D03*
Y928779D03*
X160827Y597091D03*
G54D13*
X8900Y139356D03*
Y142506D03*
X22500Y255425D03*
Y258575D03*
X10600Y862925D03*
Y866075D03*
X17500Y980925D03*
Y984075D03*
X53500Y801075D03*
Y797925D03*
X72500Y70575D03*
Y67425D03*
X59500Y104425D03*
Y107575D03*
Y89425D03*
Y92575D03*
X71500Y127575D03*
Y124425D03*
X56500Y292575D03*
Y289425D03*
X59500Y434925D03*
Y438075D03*
Y448925D03*
Y452075D03*
X72000Y769925D03*
Y773075D03*
X57500Y801075D03*
Y797925D03*
X75500Y846425D03*
Y849575D03*
X63500Y1019575D03*
Y1016425D03*
X87500Y132925D03*
Y136075D03*
X109000Y487425D03*
Y490575D03*
X144500Y71425D03*
Y74575D03*
Y85425D03*
Y88575D03*
X139000Y253925D03*
Y257075D03*
X145000Y432925D03*
X144500Y423075D03*
Y419925D03*
X145000Y436075D03*
Y779425D03*
Y782575D03*
X127000Y801425D03*
Y804575D03*
X142000Y984425D03*
Y987575D03*
X133000Y1128925D03*
Y1132075D03*
X167000Y291575D03*
Y288425D03*
X149000Y779425D03*
Y782575D03*
X179000Y387425D03*
Y390575D03*
X181500Y490075D03*
Y486925D03*
X177500D03*
Y490075D03*
X179000Y857575D03*
Y854425D03*
X172000Y1020575D03*
Y1017425D03*
X194854Y141356D03*
Y144506D03*
X197500Y869425D03*
Y872575D03*
G54D40*
X35260Y643441D03*
Y646000D03*
Y648559D03*
X42740D03*
Y646000D03*
Y643441D03*
X35260Y654441D03*
Y657000D03*
Y659559D03*
X42740D03*
Y657000D03*
Y654441D03*
X35260Y666941D03*
Y669500D03*
Y672059D03*
X42740D03*
Y669500D03*
Y666941D03*
X35260Y679441D03*
Y682000D03*
Y684559D03*
X42740D03*
Y682000D03*
Y679441D03*
G54D50*
X101339Y587000D03*
X98780D03*
X96220D03*
X93661D03*
X91102D03*
X88543D03*
X85984D03*
X83425D03*
Y610000D03*
X85984D03*
X88543D03*
X91102D03*
X93661D03*
X96220D03*
X98780D03*
X101339D03*
X111575Y587000D03*
X109016D03*
X106457D03*
X103898D03*
Y610000D03*
X106457D03*
X109016D03*
X111575D03*
G54D14*
X10000Y496500D03*
X17000D03*
X31500Y1220600D03*
X12000Y1221000D03*
X19000D03*
X27500Y1229400D03*
X35500D03*
X169000Y1229900D03*
X191500Y496000D03*
X184500D03*
X191500Y1221000D03*
X184500D03*
X173000Y1221100D03*
X177000Y1229900D03*
G54D32*
X29000Y694425D03*
Y696984D03*
Y699543D03*
Y702102D03*
Y704661D03*
Y707220D03*
Y709780D03*
Y712339D03*
Y714898D03*
Y717457D03*
Y720016D03*
Y722575D03*
X52000Y709780D03*
Y707220D03*
Y704661D03*
Y702102D03*
Y699543D03*
Y696984D03*
Y694425D03*
Y722575D03*
Y720016D03*
Y717457D03*
Y714898D03*
Y712339D03*
X131500Y661425D03*
Y663984D03*
Y666543D03*
Y669102D03*
Y671661D03*
Y674220D03*
Y676780D03*
Y679339D03*
Y681898D03*
Y684457D03*
Y687016D03*
Y689575D03*
X131000Y707323D03*
Y709882D03*
Y712441D03*
Y715000D03*
Y717559D03*
Y720118D03*
Y722677D03*
X131500Y738323D03*
Y740882D03*
Y743441D03*
Y746000D03*
Y748559D03*
Y751118D03*
Y753677D03*
X154500Y663984D03*
Y661425D03*
Y687016D03*
Y684457D03*
Y681898D03*
Y679339D03*
Y676780D03*
Y674220D03*
Y671661D03*
Y669102D03*
Y666543D03*
Y689575D03*
X154000Y709882D03*
Y707323D03*
Y722677D03*
Y720118D03*
Y717559D03*
Y715000D03*
Y712441D03*
X154500Y753677D03*
Y751118D03*
Y748559D03*
Y746000D03*
Y743441D03*
Y740882D03*
Y738323D03*
G54D41*
X77900Y63000D03*
X72100D03*
X76743Y119500D03*
X70943D03*
X78400Y415000D03*
X72600D03*
X77400Y778000D03*
X71600D03*
X76900Y828500D03*
X71100D03*
X76400Y1134000D03*
X70600D03*
X76400Y1191000D03*
X70600D03*
X79600Y858500D03*
X85400D03*
X110400Y121000D03*
X104600D03*
X125100Y461000D03*
Y1192500D03*
X126600Y59500D03*
X132400D03*
X126875Y399500D03*
X132675D03*
X130900Y461000D03*
X132100Y766500D03*
X137900D03*
X126100Y829114D03*
X131900D03*
X126600Y1137500D03*
X132400D03*
X130900Y1192500D03*
X166600Y389000D03*
X172400D03*
G54D23*
X29484Y259500D03*
X16484Y502000D03*
Y511000D03*
Y515500D03*
Y506500D03*
Y520000D03*
X26984Y641000D03*
Y645500D03*
Y660000D03*
Y654000D03*
Y686000D03*
Y680500D03*
Y672500D03*
Y666500D03*
X12484Y734000D03*
X22984D03*
X16484Y723000D03*
Y719000D03*
X12484Y748000D03*
Y741000D03*
X22984Y748000D03*
Y741000D03*
X24984Y981500D03*
Y985500D03*
X35775Y268728D03*
X52484Y293000D03*
X46545Y282728D03*
X35775Y995500D03*
X47045Y1009500D03*
X58027Y75342D03*
X57984Y84192D03*
X66527Y75342D03*
X60045Y283728D03*
X74984Y410000D03*
X66027Y401378D03*
X57984Y429228D03*
X58027Y420378D03*
X66527D03*
X71984Y475000D03*
X62984Y641000D03*
Y660000D03*
Y655400D03*
Y647000D03*
Y685000D03*
Y679000D03*
Y672500D03*
Y666500D03*
X73984Y729000D03*
Y738500D03*
Y734500D03*
X66027Y764764D03*
X57984Y792614D03*
X58027Y783764D03*
X66527D03*
X76984Y834000D03*
X60545Y1010500D03*
X59484Y1020000D03*
X58027Y1147650D03*
X75027Y1142650D03*
X66527Y1147650D03*
X66027Y1128650D03*
X57984Y1164000D03*
X100984Y81551D03*
X88484Y450500D03*
X83484Y672000D03*
Y680000D03*
Y688000D03*
Y696000D03*
Y704000D03*
Y709500D03*
Y715000D03*
X115984Y83500D03*
X124984Y66500D03*
X101984Y493500D03*
Y503500D03*
Y509500D03*
Y521500D03*
Y531500D03*
X115484Y659500D03*
Y663500D03*
X120984Y704000D03*
Y711000D03*
Y718000D03*
Y731000D03*
Y738000D03*
Y745000D03*
X145984Y249000D03*
Y257000D03*
X127484Y435000D03*
X134484Y656500D03*
X125484Y694500D03*
X133484D03*
X138484Y762000D03*
X147484Y980500D03*
X148484Y103342D03*
X148984Y126842D03*
X159466Y268728D03*
X169342Y283728D03*
X161984Y292000D03*
X155842Y282728D03*
X148484Y447228D03*
X148984Y470728D03*
X166984Y720000D03*
Y713000D03*
Y747000D03*
Y740000D03*
Y754000D03*
X148484Y810614D03*
X148984Y834114D03*
X159466Y998649D03*
X169342Y1010500D03*
X148984Y989000D03*
X155842Y1009500D03*
X167984Y1021500D03*
X148484Y1174000D03*
X148984Y1197500D03*
X183984Y663500D03*
Y659500D03*
Y652000D03*
X172984Y684500D03*
Y680500D03*
Y676500D03*
Y672500D03*
Y668500D03*
X178984Y706000D03*
X172984Y696500D03*
Y692500D03*
Y688500D03*
X190984Y706000D03*
X178984Y733000D03*
X187484D03*
G54D33*
X30100Y735500D03*
Y740500D03*
Y745500D03*
Y750500D03*
X50900D03*
Y745500D03*
Y740500D03*
Y735500D03*
G54D51*
X101772Y1287047D03*
G54D42*
X77776Y500626D03*
Y516374D03*
X87224Y500626D03*
X85650D03*
X84075D03*
X82500D03*
X80925D03*
X79350D03*
Y516374D03*
X80925D03*
X82500D03*
X84075D03*
X85650D03*
X87224D03*
X124000Y500626D03*
X122425D03*
X120850D03*
X119276D03*
Y516374D03*
X120850D03*
X122425D03*
X124000D03*
X128724Y500626D03*
X127150D03*
X125575D03*
Y516374D03*
X127150D03*
X128724D03*
G54D24*
X12791Y267212D03*
Y993984D03*
X45500Y292484D03*
X55500Y389484D03*
X76500Y70484D03*
X75500Y127484D03*
X71000Y528984D03*
X68000Y576484D03*
X75000D03*
X65000Y1199984D03*
X100000Y122484D03*
X85500Y112484D03*
Y470484D03*
X87500Y486984D03*
X93000Y528984D03*
X87500D03*
X80000Y567984D03*
X91000Y631484D03*
X87000D03*
X98500D03*
X92500Y642984D03*
X84700D03*
X98500D03*
X88500Y813484D03*
X92500Y848984D03*
X85500Y833484D03*
X88500Y1176484D03*
X85500Y1196484D03*
X109500Y403484D03*
X113500Y481484D03*
X119000D03*
X124500D03*
Y490484D03*
X109000Y481484D03*
X105000Y631484D03*
X121000D03*
X114000D03*
X107000Y642984D03*
X121000D03*
X114000D03*
X111500Y768484D03*
X112500Y1131484D03*
X127000Y74484D03*
Y88484D03*
X136482Y267212D03*
X127500Y421484D03*
X135500Y481484D03*
X130000D03*
Y490484D03*
X135000Y631484D03*
X131000D03*
X138500Y642984D03*
X126500D03*
X127000Y783984D03*
Y796984D03*
X136482Y997133D03*
X127000Y1148484D03*
Y1162484D03*
X138500Y1183484D03*
X154500Y291484D03*
X148500Y390484D03*
G54D15*
X9517Y734000D03*
Y748000D03*
Y741000D03*
X26517Y259500D03*
X13517Y502000D03*
Y511000D03*
Y515500D03*
Y506500D03*
Y520000D03*
X24017Y641000D03*
Y645500D03*
Y660000D03*
Y654000D03*
Y686000D03*
Y680500D03*
Y672500D03*
Y666500D03*
X20017Y734000D03*
X13517Y723000D03*
Y719000D03*
X20017Y748000D03*
Y741000D03*
X22017Y981500D03*
Y985500D03*
X55060Y75342D03*
X55017Y84192D03*
X32808Y268728D03*
X49517Y293000D03*
X43578Y282728D03*
X55017Y429228D03*
X55060Y420378D03*
X55017Y792614D03*
X55060Y783764D03*
X32808Y995500D03*
X44078Y1009500D03*
X55060Y1147650D03*
X55017Y1164000D03*
X63560Y75342D03*
X57078Y283728D03*
X72017Y410000D03*
X63060Y401378D03*
X63560Y420378D03*
X69017Y475000D03*
X60017Y641000D03*
Y660000D03*
Y655400D03*
Y647000D03*
Y685000D03*
Y679000D03*
Y672500D03*
Y666500D03*
X71017Y729000D03*
Y738500D03*
Y734500D03*
X63060Y764764D03*
X63560Y783764D03*
X74017Y834000D03*
X57578Y1010500D03*
X56517Y1020000D03*
X72060Y1142650D03*
X63560Y1147650D03*
X63060Y1128650D03*
X98017Y81551D03*
X85517Y450500D03*
X99017Y493500D03*
Y503500D03*
Y509500D03*
Y521500D03*
Y531500D03*
X80517Y672000D03*
Y680000D03*
Y688000D03*
Y696000D03*
Y704000D03*
Y709500D03*
Y715000D03*
X113017Y83500D03*
X122017Y66500D03*
X124517Y435000D03*
X112517Y659500D03*
Y663500D03*
X118017Y704000D03*
Y711000D03*
X122517Y694500D03*
X118017Y718000D03*
Y731000D03*
Y738000D03*
Y745000D03*
X145517Y103342D03*
X146017Y126842D03*
X143017Y249000D03*
Y257000D03*
X145517Y447228D03*
X146017Y470728D03*
X131517Y656500D03*
X130517Y694500D03*
X135517Y762000D03*
X145517Y810614D03*
X146017Y834114D03*
X144517Y980500D03*
X146017Y989000D03*
X145517Y1174000D03*
X146017Y1197500D03*
X156499Y268728D03*
X166375Y283728D03*
X159017Y292000D03*
X152875Y282728D03*
X170017Y684500D03*
Y680500D03*
Y676500D03*
Y672500D03*
Y668500D03*
Y696500D03*
Y692500D03*
Y688500D03*
X164017Y720000D03*
Y713000D03*
Y747000D03*
Y740000D03*
Y754000D03*
X156499Y998649D03*
X166375Y1010500D03*
X152875Y1009500D03*
X165017Y1021500D03*
X181017Y663500D03*
Y659500D03*
Y652000D03*
X176017Y706000D03*
X188017D03*
X176017Y733000D03*
X184517D03*
G54D34*
X15500Y1227850D03*
X12941Y1234150D03*
X18059D03*
X188000Y1228850D03*
X185441Y1235150D03*
X190559D03*
G54D52*
X116772Y19685D03*
G54D43*
X82500Y508500D03*
X124000D03*
G54D25*
X12791Y264245D03*
Y991017D03*
X45500Y289517D03*
X55500Y386517D03*
X76500Y67517D03*
X75500Y124517D03*
X71000Y526017D03*
X68000Y573517D03*
X75000D03*
X65000Y1197017D03*
X85500Y109517D03*
X100000Y119517D03*
X85500Y467517D03*
X87500Y484017D03*
X93000Y526017D03*
X87500D03*
X80000Y565017D03*
X92500Y640017D03*
X84700D03*
X98500D03*
X91000Y628517D03*
X87000D03*
X98500D03*
X88500Y810517D03*
X92500Y846017D03*
X85500Y830517D03*
X88500Y1173517D03*
X85500Y1193517D03*
X109500Y400517D03*
X113500Y478517D03*
X119000D03*
X124500D03*
X109000D03*
X124500Y487517D03*
X107000Y640017D03*
X121000D03*
X114000D03*
X105000Y628517D03*
X121000D03*
X114000D03*
X111500Y765517D03*
X112500Y1128517D03*
X127000Y71517D03*
Y85517D03*
X136482Y264245D03*
X127500Y418517D03*
X135500Y478517D03*
X130000D03*
Y487517D03*
X135000Y628517D03*
X131000D03*
X138500Y640017D03*
X126500D03*
X127000Y781017D03*
Y794017D03*
X136482Y994166D03*
X127000Y1145517D03*
Y1159517D03*
X138500Y1180517D03*
X154500Y288517D03*
X148500Y387517D03*
G54D16*
X30315Y41378D03*
Y404764D03*
Y768150D03*
Y1131536D03*
X173228Y111456D03*
Y474842D03*
Y838228D03*
Y1201614D03*
G54D53*
G01X0Y1311024D02*
Y15748D01*
G01D02*
G03X15748Y0I15748J0D01*
G01Y1326772D02*
G03X0Y1311024I0J-15748D01*
G01X15748Y0D02*
X58898D01*
G01X187795Y1326772D02*
X15748D01*
G01X58898Y0D02*
X64803Y5906D01*
G01D02*
Y43307D01*
G01X74252D02*
Y7283D01*
G01D02*
X80157Y1378D01*
G01X64803Y43307D02*
G02X74252I4724J0D01*
G01X80157Y1378D02*
X99488D01*
G01D02*
X105394Y7283D01*
G01D02*
Y43307D01*
G01X108150D02*
Y7283D01*
G01D02*
X114055Y1378D01*
G01D02*
X123386D01*
G01D02*
X129291Y7283D01*
G01X105394Y43307D02*
G02X108150I1378J0D01*
G01X138740Y5906D02*
X144646Y0D01*
G01D02*
X187795D01*
G01X129291Y7283D02*
Y43307D01*
G01X138740D02*
Y5906D01*
G01X129291Y43307D02*
G02X138740I4724J0D01*
G01X187795Y0D02*
G03X203543Y15748I0J15748D01*
G01Y1311024D02*
G03X187795Y1326772I-15748J0D01*
G01X203543Y15748D02*
Y1311024D01*
G54D35*
X20000Y1307000D03*
X44000Y17500D03*
X178500D03*
G54D26*
X28579Y508429D03*
X30547D03*
Y524571D03*
X28579D03*
X38421Y508429D03*
Y524571D03*
X32516Y508429D03*
X34484D03*
X36453D03*
Y524571D03*
X34484D03*
X32516D03*
X170047Y509929D03*
X168079D03*
Y526071D03*
X170047D03*
X177921Y509929D03*
X175953D03*
X173984D03*
X172016D03*
Y526071D03*
X173984D03*
X175953D03*
X177921D03*
G54D44*
X74626Y503776D03*
Y505350D03*
Y506925D03*
Y508500D03*
Y510075D03*
Y511650D03*
Y513224D03*
X90374D03*
Y511650D03*
Y510075D03*
Y508500D03*
Y506925D03*
Y505350D03*
Y503776D03*
X116126D03*
Y505350D03*
Y506925D03*
Y508500D03*
Y510075D03*
Y511650D03*
Y513224D03*
X131874D03*
Y511650D03*
Y510075D03*
Y508500D03*
Y506925D03*
Y505350D03*
Y503776D03*
G54D17*
X34252Y64606D03*
Y56732D03*
Y48858D03*
X26378Y64606D03*
Y56732D03*
X34252Y88228D03*
Y80354D03*
Y72480D03*
X26378Y88228D03*
Y80354D03*
Y72480D03*
X34252Y103976D03*
Y96102D03*
X26378Y103976D03*
Y96102D03*
X34252Y412244D03*
Y435866D03*
Y427992D03*
Y420118D03*
X26378Y435866D03*
Y427992D03*
Y420118D03*
X34252Y451614D03*
Y443740D03*
X26378Y451614D03*
Y443740D03*
X34252Y467362D03*
Y459488D03*
X26378Y467362D03*
Y459488D03*
X34252Y775630D03*
Y799252D03*
Y791378D03*
Y783504D03*
X26378Y799252D03*
Y791378D03*
Y783504D03*
X34252Y822874D03*
Y815000D03*
Y807126D03*
X26378Y822874D03*
Y815000D03*
Y807126D03*
X34252Y830748D03*
X26378D03*
X34252Y1146890D03*
Y1139016D03*
X26378Y1146890D03*
X34252Y1170512D03*
Y1162638D03*
Y1154764D03*
X26378Y1170512D03*
Y1162638D03*
Y1154764D03*
X34252Y1194134D03*
Y1186260D03*
Y1178386D03*
X26378Y1194134D03*
Y1186260D03*
Y1178386D03*
X169291Y48858D03*
Y56732D03*
Y64606D03*
Y72480D03*
Y80354D03*
Y88228D03*
Y96102D03*
Y103976D03*
Y412244D03*
Y420118D03*
Y427992D03*
Y435866D03*
Y443740D03*
Y451614D03*
Y459488D03*
Y467362D03*
Y775630D03*
Y783504D03*
Y791378D03*
Y799252D03*
Y807126D03*
Y815000D03*
Y822874D03*
Y830748D03*
Y1139016D03*
Y1146890D03*
Y1154764D03*
Y1162638D03*
Y1170512D03*
Y1178386D03*
Y1186260D03*
Y1194134D03*
X177165Y48858D03*
Y56732D03*
Y64606D03*
Y72480D03*
Y80354D03*
Y88228D03*
Y96102D03*
Y412244D03*
Y420118D03*
Y427992D03*
Y435866D03*
Y443740D03*
Y451614D03*
Y459488D03*
Y775630D03*
Y783504D03*
Y791378D03*
Y799252D03*
Y807126D03*
Y815000D03*
Y822874D03*
Y1139016D03*
Y1146890D03*
Y1154764D03*
Y1162638D03*
Y1170512D03*
Y1178386D03*
Y1186260D03*
G54D54*
G01X-320500Y-470483D02*
Y2626000D01*
X2967000D01*
Y-470483D01*
X-320500D01*
G01X329322Y-314459D02*
Y-319459D01*
G01X327865Y-314459D02*
X330779D01*
G01X335689Y-319459D02*
X333155D01*
Y-314459D01*
X335689D01*
G01X334675Y-316876D02*
X333155D01*
G01X338255Y-314459D02*
Y-319459D01*
X340789D01*
G01X344622Y-319626D02*
X344495Y-319542D01*
Y-319376D01*
X344622Y-319292D01*
X344749Y-319376D01*
Y-319542D01*
X344622Y-319626D01*
G01Y-317376D02*
X344495Y-317292D01*
Y-317126D01*
X344622Y-317042D01*
X344749Y-317126D01*
Y-317292D01*
X344622Y-317376D01*
G01X349405Y-321126D02*
X348772Y-320292D01*
X348455Y-319459D01*
Y-316126D01*
X348772Y-315292D01*
X349405Y-314459D01*
G01X354822D02*
X354315Y-314626D01*
X353935Y-315042D01*
X353682Y-315542D01*
X353492Y-316209D01*
X353429Y-316959D01*
X353492Y-317709D01*
X353682Y-318376D01*
X353935Y-318876D01*
X354315Y-319292D01*
X354822Y-319459D01*
X355329Y-319292D01*
X355709Y-318876D01*
X355962Y-318376D01*
X356152Y-317709D01*
X356215Y-316959D01*
X356152Y-316209D01*
X355962Y-315542D01*
X355709Y-315042D01*
X355329Y-314626D01*
X354822Y-314459D01*
G01X358529Y-318459D02*
X358909Y-319042D01*
X359415Y-319376D01*
X359985Y-319459D01*
X360492Y-319376D01*
X360999Y-318959D01*
X361315Y-318459D01*
X361379Y-317959D01*
X361252Y-317376D01*
X360809Y-316959D01*
X360365Y-316792D01*
X359795D01*
G01X360365D02*
X360745Y-316542D01*
X361062Y-316126D01*
X361189Y-315626D01*
X361062Y-315126D01*
X360745Y-314709D01*
X360175Y-314459D01*
X359605Y-314542D01*
X359035Y-314876D01*
G01X365339Y-321126D02*
X365972Y-320292D01*
X366289Y-319459D01*
Y-316126D01*
X365972Y-315292D01*
X365339Y-314459D01*
G01X368729Y-318459D02*
X369109Y-319042D01*
X369615Y-319376D01*
X370185Y-319459D01*
X370692Y-319376D01*
X371199Y-318959D01*
X371515Y-318459D01*
X371579Y-317959D01*
X371452Y-317376D01*
X371009Y-316959D01*
X370565Y-316792D01*
X369995D01*
G01X370565D02*
X370945Y-316542D01*
X371262Y-316126D01*
X371389Y-315626D01*
X371262Y-315126D01*
X370945Y-314709D01*
X370375Y-314459D01*
X369805Y-314542D01*
X369235Y-314876D01*
G01X374019Y-315292D02*
X374399Y-314792D01*
X374842Y-314542D01*
X375349Y-314459D01*
X375982Y-314626D01*
X376425Y-315042D01*
X376552Y-315542D01*
X376489Y-316042D01*
X376235Y-316459D01*
X374969Y-317292D01*
X374399Y-317876D01*
X374019Y-318709D01*
X373892Y-319459D01*
X376552D01*
G01X380195D02*
X380322Y-318376D01*
X380512Y-317459D01*
X380765Y-316626D01*
X381082Y-315709D01*
X381589Y-314459D01*
X379055D01*
G01X384599Y-317792D02*
X386245D01*
G01X389319Y-315292D02*
X389699Y-314792D01*
X390142Y-314542D01*
X390649Y-314459D01*
X391282Y-314626D01*
X391725Y-315042D01*
X391852Y-315542D01*
X391789Y-316042D01*
X391535Y-316459D01*
X390269Y-317292D01*
X389699Y-317876D01*
X389319Y-318709D01*
X389192Y-319459D01*
X391852D01*
G01X394229Y-318459D02*
X394609Y-319042D01*
X395115Y-319376D01*
X395685Y-319459D01*
X396192Y-319376D01*
X396699Y-318959D01*
X397015Y-318459D01*
X397079Y-317959D01*
X396952Y-317376D01*
X396509Y-316959D01*
X396065Y-316792D01*
X395495D01*
G01X396065D02*
X396445Y-316542D01*
X396762Y-316126D01*
X396889Y-315626D01*
X396762Y-315126D01*
X396445Y-314709D01*
X395875Y-314459D01*
X395305Y-314542D01*
X394735Y-314876D01*
G01X401482Y-319459D02*
Y-314459D01*
X399139Y-318042D01*
X402305D01*
G01X404429Y-318709D02*
X404809Y-319126D01*
X405252Y-319376D01*
X405822Y-319459D01*
X406392Y-319292D01*
X406835Y-318959D01*
X407152Y-318376D01*
X407215Y-317709D01*
X407089Y-317042D01*
X406772Y-316626D01*
X406329Y-316292D01*
X405885Y-316209D01*
X405442Y-316292D01*
X404872Y-316626D01*
X405062Y-314459D01*
X406772D01*
G01X414819Y-319459D02*
Y-314459D01*
X417225D01*
G01X416339Y-316876D02*
X414819D01*
G01X419539Y-319459D02*
X421122Y-314459D01*
X422705Y-319459D01*
G01X422135Y-317709D02*
X420109D01*
G01X424892Y-319459D02*
X427552Y-314459D01*
G01X424892D02*
X427552Y-319459D01*
G01X431322Y-319626D02*
X431195Y-319542D01*
Y-319376D01*
X431322Y-319292D01*
X431449Y-319376D01*
Y-319542D01*
X431322Y-319626D01*
G01Y-317376D02*
X431195Y-317292D01*
Y-317126D01*
X431322Y-317042D01*
X431449Y-317126D01*
Y-317292D01*
X431322Y-317376D01*
G01X436105Y-321126D02*
X435472Y-320292D01*
X435155Y-319459D01*
Y-316126D01*
X435472Y-315292D01*
X436105Y-314459D01*
G01X441522D02*
X441015Y-314626D01*
X440635Y-315042D01*
X440382Y-315542D01*
X440192Y-316209D01*
X440129Y-316959D01*
X440192Y-317709D01*
X440382Y-318376D01*
X440635Y-318876D01*
X441015Y-319292D01*
X441522Y-319459D01*
X442029Y-319292D01*
X442409Y-318876D01*
X442662Y-318376D01*
X442852Y-317709D01*
X442915Y-316959D01*
X442852Y-316209D01*
X442662Y-315542D01*
X442409Y-315042D01*
X442029Y-314626D01*
X441522Y-314459D01*
G01X445229Y-318459D02*
X445609Y-319042D01*
X446115Y-319376D01*
X446685Y-319459D01*
X447192Y-319376D01*
X447699Y-318959D01*
X448015Y-318459D01*
X448079Y-317959D01*
X447952Y-317376D01*
X447509Y-316959D01*
X447065Y-316792D01*
X446495D01*
G01X447065D02*
X447445Y-316542D01*
X447762Y-316126D01*
X447889Y-315626D01*
X447762Y-315126D01*
X447445Y-314709D01*
X446875Y-314459D01*
X446305Y-314542D01*
X445735Y-314876D01*
G01X452039Y-321126D02*
X452672Y-320292D01*
X452989Y-319459D01*
Y-316126D01*
X452672Y-315292D01*
X452039Y-314459D01*
G01X455429Y-318459D02*
X455809Y-319042D01*
X456315Y-319376D01*
X456885Y-319459D01*
X457392Y-319376D01*
X457899Y-318959D01*
X458215Y-318459D01*
X458279Y-317959D01*
X458152Y-317376D01*
X457709Y-316959D01*
X457265Y-316792D01*
X456695D01*
G01X457265D02*
X457645Y-316542D01*
X457962Y-316126D01*
X458089Y-315626D01*
X457962Y-315126D01*
X457645Y-314709D01*
X457075Y-314459D01*
X456505Y-314542D01*
X455935Y-314876D01*
G01X460845Y-318876D02*
X461289Y-319292D01*
X461795Y-319459D01*
X462302Y-319292D01*
X462745Y-318792D01*
X463062Y-318042D01*
X463189Y-317292D01*
Y-316376D01*
X463062Y-315626D01*
X462745Y-314959D01*
X462365Y-314626D01*
X461922Y-314459D01*
X461415Y-314626D01*
X461035Y-314959D01*
X460782Y-315459D01*
X460655Y-316126D01*
X460782Y-316709D01*
X461099Y-317292D01*
X461479Y-317626D01*
X461922Y-317709D01*
X462429Y-317542D01*
X462809Y-317126D01*
X463189Y-316376D01*
G01X466895Y-319459D02*
X467022Y-318376D01*
X467212Y-317459D01*
X467465Y-316626D01*
X467782Y-315709D01*
X468289Y-314459D01*
X465755D01*
G01X471299Y-317792D02*
X472945D01*
G01X475829Y-318459D02*
X476209Y-319042D01*
X476715Y-319376D01*
X477285Y-319459D01*
X477792Y-319376D01*
X478299Y-318959D01*
X478615Y-318459D01*
X478679Y-317959D01*
X478552Y-317376D01*
X478109Y-316959D01*
X477665Y-316792D01*
X477095D01*
G01X477665D02*
X478045Y-316542D01*
X478362Y-316126D01*
X478489Y-315626D01*
X478362Y-315126D01*
X478045Y-314709D01*
X477475Y-314459D01*
X476905Y-314542D01*
X476335Y-314876D01*
G01X481119Y-317376D02*
X481562Y-316792D01*
X481942Y-316459D01*
X482449Y-316292D01*
X482892Y-316459D01*
X483209Y-316792D01*
X483462Y-317292D01*
X483525Y-317876D01*
X483462Y-318376D01*
X483209Y-318876D01*
X482829Y-319292D01*
X482385Y-319459D01*
X481879Y-319292D01*
X481435Y-318792D01*
X481182Y-318042D01*
X481119Y-317209D01*
X481245Y-316126D01*
X481435Y-315542D01*
X481752Y-314959D01*
X482195Y-314542D01*
X482639Y-314459D01*
X483082Y-314626D01*
X483399Y-315042D01*
G01X487422Y-319459D02*
Y-314459D01*
X486662Y-315459D01*
G01Y-319459D02*
X488182D01*
G01X493282D02*
Y-314459D01*
X490939Y-318042D01*
X494105D01*
G01X317322Y-249459D02*
Y-324459D01*
X817322D01*
Y-249459D01*
X317322D01*
G01X512322D02*
Y-324459D01*
G01Y-299459D02*
X615322D01*
Y-274459D01*
G01X512322D02*
X615322D01*
G01X622829Y-309459D02*
Y-304459D01*
X624095D01*
X624602Y-304709D01*
X624982Y-305042D01*
X625299Y-305542D01*
X625552Y-306126D01*
X625615Y-306959D01*
X625552Y-307792D01*
X625299Y-308376D01*
X624982Y-308876D01*
X624602Y-309209D01*
X624095Y-309459D01*
X622829D01*
G01X627739D02*
X629322Y-304459D01*
X630905Y-309459D01*
G01X630335Y-307709D02*
X628309D01*
G01X634422Y-304459D02*
Y-309459D01*
G01X632965Y-304459D02*
X635879D01*
G01X640789Y-309459D02*
X638255D01*
Y-304459D01*
X640789D01*
G01X639775Y-306876D02*
X638255D01*
G01X644622Y-309626D02*
X644495Y-309542D01*
Y-309376D01*
X644622Y-309292D01*
X644749Y-309376D01*
Y-309542D01*
X644622Y-309626D01*
G01Y-307376D02*
X644495Y-307292D01*
Y-307126D01*
X644622Y-307042D01*
X644749Y-307126D01*
Y-307292D01*
X644622Y-307376D01*
G01X617322Y-249459D02*
Y-324459D01*
G01X615322Y-249459D02*
Y-324459D01*
G01X622955Y-284459D02*
Y-279459D01*
X624475D01*
X624982Y-279709D01*
X625362Y-280292D01*
X625489Y-280959D01*
X625362Y-281626D01*
X625045Y-282126D01*
X624475Y-282376D01*
X622955D01*
G01X628182Y-284626D02*
X630462Y-279459D01*
G01X632965Y-284459D02*
Y-279459D01*
X635879Y-284459D01*
Y-279459D01*
G01X639522Y-284626D02*
X639395Y-284542D01*
Y-284376D01*
X639522Y-284292D01*
X639649Y-284376D01*
Y-284542D01*
X639522Y-284626D01*
G01Y-282376D02*
X639395Y-282292D01*
Y-282126D01*
X639522Y-282042D01*
X639649Y-282126D01*
Y-282292D01*
X639522Y-282376D01*
G01X617322Y-299459D02*
X817322D01*
G01X622955Y-259459D02*
Y-254459D01*
X624475D01*
X624982Y-254709D01*
X625362Y-255292D01*
X625489Y-255959D01*
X625362Y-256626D01*
X625045Y-257126D01*
X624475Y-257376D01*
X622955D01*
G01X628055Y-259459D02*
Y-254459D01*
X629639D01*
X630145Y-254709D01*
X630462Y-255042D01*
X630589Y-255709D01*
X630462Y-256376D01*
X630082Y-256792D01*
X629639Y-257042D01*
X628055D01*
G01X629639D02*
X630589Y-259459D01*
G01X634422D02*
X633915Y-259376D01*
X633472Y-259042D01*
X633092Y-258542D01*
X632839Y-257959D01*
X632712Y-257292D01*
Y-256626D01*
X632839Y-255959D01*
X633092Y-255376D01*
X633472Y-254876D01*
X633915Y-254542D01*
X634422Y-254459D01*
X634929Y-254542D01*
X635372Y-254876D01*
X635752Y-255376D01*
X636005Y-255959D01*
X636132Y-256626D01*
Y-257292D01*
X636005Y-257959D01*
X635752Y-258542D01*
X635372Y-259042D01*
X634929Y-259376D01*
X634422Y-259459D01*
G01X638255Y-258459D02*
X638572Y-258959D01*
X638952Y-259292D01*
X639395Y-259459D01*
X639902Y-259292D01*
X640282Y-258959D01*
X640662Y-258459D01*
X640789Y-257792D01*
Y-254459D01*
G01X645889Y-259459D02*
X643355D01*
Y-254459D01*
X645889D01*
G01X644875Y-256876D02*
X643355D01*
G01X651115Y-254876D02*
X650735Y-254626D01*
X650292Y-254459D01*
X649785D01*
X649215Y-254709D01*
X648772Y-255126D01*
X648455Y-255626D01*
X648202Y-256459D01*
X648139Y-257209D01*
X648265Y-257959D01*
X648455Y-258459D01*
X648835Y-258959D01*
X649279Y-259292D01*
X649722Y-259459D01*
X650165D01*
X650609Y-259292D01*
X650989Y-259042D01*
X651305Y-258709D01*
G01X654822Y-254459D02*
Y-259459D01*
G01X653365Y-254459D02*
X656279D01*
G01X659922Y-259626D02*
X659795Y-259542D01*
Y-259376D01*
X659922Y-259292D01*
X660049Y-259376D01*
Y-259542D01*
X659922Y-259626D01*
G01Y-257376D02*
X659795Y-257292D01*
Y-257126D01*
X659922Y-257042D01*
X660049Y-257126D01*
Y-257292D01*
X659922Y-257376D01*
G01X617322Y-274459D02*
X817322D01*
G01X734955Y-301959D02*
Y-306959D01*
X737489D01*
G01X740562Y-301959D02*
X742082D01*
G01X741322D02*
Y-306959D01*
G01X740562D02*
X742082D01*
G01X746929Y-304292D02*
X747182Y-304042D01*
X747372Y-303626D01*
X747499Y-303042D01*
X747372Y-302542D01*
X747119Y-302209D01*
X746675Y-301959D01*
X744965D01*
Y-306959D01*
X747055D01*
X747499Y-306626D01*
X747752Y-306126D01*
X747879Y-305542D01*
X747752Y-304959D01*
X747372Y-304459D01*
X746929Y-304292D01*
X744965D01*
G01X751522Y-307126D02*
X751395Y-307042D01*
Y-306876D01*
X751522Y-306792D01*
X751649Y-306876D01*
Y-307042D01*
X751522Y-307126D01*
G01Y-304876D02*
X751395Y-304792D01*
Y-304626D01*
X751522Y-304542D01*
X751649Y-304626D01*
Y-304792D01*
X751522Y-304876D01*
G01X732322Y-299459D02*
Y-324459D01*
G01X779222Y-301959D02*
Y-306959D01*
G01X777765Y-301959D02*
X780679D01*
G01X784322Y-306959D02*
X783942Y-306876D01*
X783562Y-306542D01*
X783309Y-305959D01*
X783182Y-305292D01*
X783309Y-304626D01*
X783562Y-304042D01*
X783942Y-303709D01*
X784322Y-303626D01*
X784702Y-303709D01*
X785082Y-304042D01*
X785335Y-304626D01*
X785399Y-305292D01*
X785335Y-305959D01*
X785082Y-306542D01*
X784702Y-306876D01*
X784322Y-306959D01*
G01X789422D02*
X789042Y-306876D01*
X788662Y-306542D01*
X788409Y-305959D01*
X788282Y-305292D01*
X788409Y-304626D01*
X788662Y-304042D01*
X789042Y-303709D01*
X789422Y-303626D01*
X789802Y-303709D01*
X790182Y-304042D01*
X790435Y-304626D01*
X790499Y-305292D01*
X790435Y-305959D01*
X790182Y-306542D01*
X789802Y-306876D01*
X789422Y-306959D01*
G01X794522D02*
Y-301959D01*
G01X799622Y-307126D02*
X799495Y-307042D01*
Y-306876D01*
X799622Y-306792D01*
X799749Y-306876D01*
Y-307042D01*
X799622Y-307126D01*
G01Y-304876D02*
X799495Y-304792D01*
Y-304626D01*
X799622Y-304542D01*
X799749Y-304626D01*
Y-304792D01*
X799622Y-304876D01*
G01X775322Y-299459D02*
Y-324459D01*
G01Y-274459D02*
Y-299459D01*
G01X777955Y-281959D02*
Y-276959D01*
X779539D01*
X780045Y-277209D01*
X780362Y-277542D01*
X780489Y-278209D01*
X780362Y-278876D01*
X779982Y-279292D01*
X779539Y-279542D01*
X777955D01*
G01X779539D02*
X780489Y-281959D01*
G01X785589D02*
X783055D01*
Y-276959D01*
X785589D01*
G01X784575Y-279376D02*
X783055D01*
G01X787839Y-276959D02*
X789422Y-281959D01*
X791005Y-276959D01*
G01X794522Y-282126D02*
X794395Y-282042D01*
Y-281876D01*
X794522Y-281792D01*
X794649Y-281876D01*
Y-282042D01*
X794522Y-282126D01*
G01Y-279876D02*
X794395Y-279792D01*
Y-279626D01*
X794522Y-279542D01*
X794649Y-279626D01*
Y-279792D01*
X794522Y-279876D01*
G01X798082Y-326159D02*
X798162Y-326084D01*
X798222Y-325959D01*
X798262Y-325784D01*
X798222Y-325634D01*
X798142Y-325534D01*
X798002Y-325459D01*
X797462D01*
Y-326959D01*
X798122D01*
X798262Y-326859D01*
X798342Y-326709D01*
X798382Y-326534D01*
X798342Y-326359D01*
X798222Y-326209D01*
X798082Y-326159D01*
X797462D01*
G01X799482Y-326959D02*
Y-325959D01*
G01Y-326134D02*
X799402Y-326034D01*
X799282Y-325984D01*
X799142Y-325959D01*
X799002Y-326009D01*
X798882Y-326109D01*
X798802Y-326259D01*
X798762Y-326459D01*
X798802Y-326659D01*
X798882Y-326809D01*
X799002Y-326909D01*
X799142Y-326959D01*
X799282Y-326934D01*
X799402Y-326859D01*
X799482Y-326759D01*
G01X800022Y-326784D02*
X800122Y-326884D01*
X800262Y-326959D01*
X800382D01*
X800502Y-326909D01*
X800582Y-326834D01*
X800622Y-326734D01*
X800602Y-326584D01*
X800522Y-326509D01*
X800162Y-326359D01*
X800082Y-326184D01*
X800122Y-326059D01*
X800202Y-325984D01*
X800322Y-325959D01*
X800442Y-325984D01*
X800562Y-326059D01*
G01X801222Y-326284D02*
X801862D01*
X801802Y-326109D01*
X801702Y-326009D01*
X801562Y-325959D01*
X801422Y-325984D01*
X801302Y-326059D01*
X801222Y-326234D01*
X801182Y-326384D01*
Y-326534D01*
X801222Y-326684D01*
X801322Y-326834D01*
X801442Y-326934D01*
X801582Y-326959D01*
X801722Y-326909D01*
X801862Y-326759D01*
G01X802362Y-326959D02*
Y-325459D01*
G01Y-326209D02*
X802462Y-326059D01*
X802582Y-325984D01*
X802702Y-325959D01*
X802882Y-326009D01*
X803002Y-326109D01*
X803082Y-326284D01*
Y-326484D01*
X803042Y-326684D01*
X802962Y-326834D01*
X802822Y-326934D01*
X802702Y-326959D01*
X802582Y-326934D01*
X802462Y-326859D01*
X802362Y-326734D01*
G01X803922Y-326959D02*
X803802Y-326934D01*
X803682Y-326834D01*
X803602Y-326659D01*
X803562Y-326459D01*
X803602Y-326259D01*
X803682Y-326084D01*
X803802Y-325984D01*
X803922Y-325959D01*
X804042Y-325984D01*
X804162Y-326084D01*
X804242Y-326259D01*
X804262Y-326459D01*
X804242Y-326659D01*
X804162Y-326834D01*
X804042Y-326934D01*
X803922Y-326959D01*
G01X805482D02*
Y-325959D01*
G01Y-326134D02*
X805402Y-326034D01*
X805282Y-325984D01*
X805142Y-325959D01*
X805002Y-326009D01*
X804882Y-326109D01*
X804802Y-326259D01*
X804762Y-326459D01*
X804802Y-326659D01*
X804882Y-326809D01*
X805002Y-326909D01*
X805142Y-326959D01*
X805282Y-326934D01*
X805402Y-326859D01*
X805482Y-326759D01*
G01X806042Y-326959D02*
Y-325959D01*
G01Y-326159D02*
X806142Y-326059D01*
X806242Y-325984D01*
X806382Y-325959D01*
X806482Y-325984D01*
X806602Y-326059D01*
G01X807882Y-325459D02*
Y-326959D01*
G01Y-326734D02*
X807802Y-326859D01*
X807682Y-326934D01*
X807542Y-326959D01*
X807382Y-326909D01*
X807262Y-326784D01*
X807182Y-326634D01*
X807162Y-326459D01*
X807182Y-326284D01*
X807262Y-326134D01*
X807382Y-326009D01*
X807542Y-325959D01*
X807682Y-325984D01*
X807782Y-326034D01*
X807882Y-326134D01*
G01X809522Y-326959D02*
Y-325459D01*
X810022D01*
X810182Y-325534D01*
X810282Y-325634D01*
X810322Y-325834D01*
X810282Y-326034D01*
X810162Y-326159D01*
X810022Y-326234D01*
X809522D01*
G01X810022D02*
X810322Y-326959D01*
G01X810822Y-326284D02*
X811462D01*
X811402Y-326109D01*
X811302Y-326009D01*
X811162Y-325959D01*
X811022Y-325984D01*
X810902Y-326059D01*
X810822Y-326234D01*
X810782Y-326384D01*
Y-326534D01*
X810822Y-326684D01*
X810922Y-326834D01*
X811042Y-326934D01*
X811182Y-326959D01*
X811322Y-326909D01*
X811462Y-326759D01*
G01X811962Y-325959D02*
X812322Y-326959D01*
X812682Y-325959D01*
G01X813522Y-327009D02*
X813482Y-326984D01*
Y-326934D01*
X813522Y-326909D01*
X813562Y-326934D01*
Y-326984D01*
X813522Y-327009D01*
G01X814682Y-326959D02*
X814722Y-326634D01*
X814782Y-326359D01*
X814862Y-326109D01*
X814962Y-325834D01*
X815122Y-325459D01*
X814322D01*
G01X816082Y-326159D02*
X816162Y-326084D01*
X816222Y-325959D01*
X816262Y-325784D01*
X816222Y-325634D01*
X816142Y-325534D01*
X816002Y-325459D01*
X815462D01*
Y-326959D01*
X816122D01*
X816262Y-326859D01*
X816342Y-326709D01*
X816382Y-326534D01*
X816342Y-326359D01*
X816222Y-326209D01*
X816082Y-326159D01*
X815462D01*
G01X-320500Y-470483D02*
Y2626000D01*
X2967000D01*
Y-470483D01*
X-320500D01*
G01X331395Y-304184D02*
X330925Y-303869D01*
X330377Y-303659D01*
X329750D01*
X329045Y-303974D01*
X328497Y-304499D01*
X328105Y-305129D01*
X327792Y-306179D01*
X327714Y-307124D01*
X327870Y-308069D01*
X328105Y-308699D01*
X328575Y-309329D01*
X329124Y-309749D01*
X329672Y-309959D01*
X330220D01*
X330769Y-309749D01*
X331239Y-309434D01*
X331630Y-309014D01*
G01X335032Y-303659D02*
X336912D01*
G01X335972D02*
Y-309959D01*
G01X335032D02*
X336912D01*
G01X342272Y-303659D02*
Y-309959D01*
G01X340470Y-303659D02*
X344074D01*
G01X348572Y-309959D02*
Y-307124D01*
X347005Y-303659D01*
G01X350139D02*
X348572Y-307124D01*
G01X359449Y-308699D02*
X359919Y-309434D01*
X360545Y-309854D01*
X361250Y-309959D01*
X361877Y-309854D01*
X362504Y-309329D01*
X362895Y-308699D01*
X362974Y-308069D01*
X362817Y-307334D01*
X362269Y-306809D01*
X361720Y-306599D01*
X361015D01*
G01X361720D02*
X362190Y-306284D01*
X362582Y-305759D01*
X362739Y-305129D01*
X362582Y-304499D01*
X362190Y-303974D01*
X361485Y-303659D01*
X360780Y-303764D01*
X360075Y-304184D01*
G01X365749Y-308699D02*
X366219Y-309434D01*
X366845Y-309854D01*
X367550Y-309959D01*
X368177Y-309854D01*
X368804Y-309329D01*
X369195Y-308699D01*
X369274Y-308069D01*
X369117Y-307334D01*
X368569Y-306809D01*
X368020Y-306599D01*
X367315D01*
G01X368020D02*
X368490Y-306284D01*
X368882Y-305759D01*
X369039Y-305129D01*
X368882Y-304499D01*
X368490Y-303974D01*
X367785Y-303659D01*
X367080Y-303764D01*
X366375Y-304184D01*
G01X372049Y-308699D02*
X372519Y-309434D01*
X373145Y-309854D01*
X373850Y-309959D01*
X374477Y-309854D01*
X375104Y-309329D01*
X375495Y-308699D01*
X375574Y-308069D01*
X375417Y-307334D01*
X374869Y-306809D01*
X374320Y-306599D01*
X373615D01*
G01X374320D02*
X374790Y-306284D01*
X375182Y-305759D01*
X375339Y-305129D01*
X375182Y-304499D01*
X374790Y-303974D01*
X374085Y-303659D01*
X373380Y-303764D01*
X372675Y-304184D01*
G01X379915Y-309959D02*
X380072Y-308594D01*
X380307Y-307439D01*
X380620Y-306389D01*
X381012Y-305234D01*
X381639Y-303659D01*
X378505D01*
G01X386215Y-309959D02*
X386372Y-308594D01*
X386607Y-307439D01*
X386920Y-306389D01*
X387312Y-305234D01*
X387939Y-303659D01*
X384805D01*
G01X392515Y-311114D02*
X392829Y-309749D01*
G01X398972Y-303659D02*
Y-309959D01*
G01X397170Y-303659D02*
X400774D01*
G01X403314Y-309959D02*
X405272Y-303659D01*
X407230Y-309959D01*
G01X406525Y-307754D02*
X404019D01*
G01X410632Y-303659D02*
X412512D01*
G01X411572D02*
Y-309959D01*
G01X410632D02*
X412512D01*
G01X415522Y-303659D02*
X416619Y-309959D01*
X417872Y-303659D01*
X419125Y-309959D01*
X420222Y-303659D01*
G01X422214Y-309959D02*
X424172Y-303659D01*
X426130Y-309959D01*
G01X425425Y-307754D02*
X422919D01*
G01X428670Y-309959D02*
Y-303659D01*
X432274Y-309959D01*
Y-303659D01*
G01X442680Y-312059D02*
X441897Y-311009D01*
X441505Y-309959D01*
Y-305759D01*
X441897Y-304709D01*
X442680Y-303659D01*
G01X454105Y-309959D02*
Y-303659D01*
X456064D01*
X456690Y-303974D01*
X457082Y-304394D01*
X457239Y-305234D01*
X457082Y-306074D01*
X456612Y-306599D01*
X456064Y-306914D01*
X454105D01*
G01X456064D02*
X457239Y-309959D01*
G01X461972Y-310169D02*
X461815Y-310064D01*
Y-309854D01*
X461972Y-309749D01*
X462129Y-309854D01*
Y-310064D01*
X461972Y-310169D01*
G01X468272Y-309959D02*
X467645Y-309854D01*
X467097Y-309434D01*
X466627Y-308804D01*
X466314Y-308069D01*
X466157Y-307229D01*
Y-306389D01*
X466314Y-305549D01*
X466627Y-304814D01*
X467097Y-304184D01*
X467645Y-303764D01*
X468272Y-303659D01*
X468899Y-303764D01*
X469447Y-304184D01*
X469917Y-304814D01*
X470230Y-305549D01*
X470387Y-306389D01*
Y-307229D01*
X470230Y-308069D01*
X469917Y-308804D01*
X469447Y-309434D01*
X468899Y-309854D01*
X468272Y-309959D01*
G01X474572Y-310169D02*
X474415Y-310064D01*
Y-309854D01*
X474572Y-309749D01*
X474729Y-309854D01*
Y-310064D01*
X474572Y-310169D01*
G01X482595Y-304184D02*
X482125Y-303869D01*
X481577Y-303659D01*
X480950D01*
X480245Y-303974D01*
X479697Y-304499D01*
X479305Y-305129D01*
X478992Y-306179D01*
X478914Y-307124D01*
X479070Y-308069D01*
X479305Y-308699D01*
X479775Y-309329D01*
X480324Y-309749D01*
X480872Y-309959D01*
X481420D01*
X481969Y-309749D01*
X482439Y-309434D01*
X482830Y-309014D01*
G01X487172Y-310169D02*
X487015Y-310064D01*
Y-309854D01*
X487172Y-309749D01*
X487329Y-309854D01*
Y-310064D01*
X487172Y-310169D01*
G01X493864Y-312059D02*
X494647Y-311009D01*
X495039Y-309959D01*
Y-305759D01*
X494647Y-304709D01*
X493864Y-303659D01*
G01X330142Y-296809D02*
X331709D01*
Y-298699D01*
X331239Y-299329D01*
X330690Y-299749D01*
X329907Y-299959D01*
X329124Y-299749D01*
X328575Y-299329D01*
X328105Y-298699D01*
X327792Y-297964D01*
X327635Y-297124D01*
Y-296389D01*
X327792Y-295759D01*
X328105Y-295024D01*
X328575Y-294394D01*
X329045Y-293974D01*
X329672Y-293659D01*
X330220D01*
X330847Y-293869D01*
X331317Y-294289D01*
G01X334249Y-293659D02*
Y-298174D01*
X334562Y-299119D01*
X335189Y-299749D01*
X335972Y-299959D01*
X336755Y-299749D01*
X337382Y-299119D01*
X337695Y-298174D01*
Y-293659D01*
G01X341332D02*
X343212D01*
G01X342272D02*
Y-299959D01*
G01X341332D02*
X343212D01*
G01X346927Y-299119D02*
X347554Y-299644D01*
X348259Y-299959D01*
X348885D01*
X349512Y-299644D01*
X349982Y-299119D01*
X350217Y-298384D01*
X350060Y-297649D01*
X349669Y-297019D01*
X348964Y-296599D01*
X348024Y-296389D01*
X347475Y-295969D01*
X347240Y-295234D01*
X347397Y-294499D01*
X347789Y-293974D01*
X348337Y-293659D01*
X348885D01*
X349434Y-293869D01*
X349904Y-294394D01*
G01X353227Y-299959D02*
Y-293659D01*
G01X356517D02*
Y-299959D01*
G01Y-296809D02*
X353227D01*
G01X359214Y-299959D02*
X361172Y-293659D01*
X363130Y-299959D01*
G01X362425Y-297754D02*
X359919D01*
G01X365670Y-299959D02*
Y-293659D01*
X369274Y-299959D01*
Y-293659D01*
G01X378349Y-299959D02*
Y-293659D01*
X379915D01*
X380542Y-293974D01*
X381012Y-294394D01*
X381404Y-295024D01*
X381717Y-295759D01*
X381795Y-296809D01*
X381717Y-297859D01*
X381404Y-298594D01*
X381012Y-299224D01*
X380542Y-299644D01*
X379915Y-299959D01*
X378349D01*
G01X385432Y-293659D02*
X387312D01*
G01X386372D02*
Y-299959D01*
G01X385432D02*
X387312D01*
G01X391027Y-299119D02*
X391654Y-299644D01*
X392359Y-299959D01*
X392985D01*
X393612Y-299644D01*
X394082Y-299119D01*
X394317Y-298384D01*
X394160Y-297649D01*
X393769Y-297019D01*
X393064Y-296599D01*
X392124Y-296389D01*
X391575Y-295969D01*
X391340Y-295234D01*
X391497Y-294499D01*
X391889Y-293974D01*
X392437Y-293659D01*
X392985D01*
X393534Y-293869D01*
X394004Y-294394D01*
G01X398972Y-293659D02*
Y-299959D01*
G01X397170Y-293659D02*
X400774D01*
G01X405272Y-300169D02*
X405115Y-300064D01*
Y-299854D01*
X405272Y-299749D01*
X405429Y-299854D01*
Y-300064D01*
X405272Y-300169D01*
G01X411415Y-301114D02*
X411729Y-299749D01*
G01X417872Y-293659D02*
Y-299959D01*
G01X416070Y-293659D02*
X419674D01*
G01X422214Y-299959D02*
X424172Y-293659D01*
X426130Y-299959D01*
G01X425425Y-297754D02*
X422919D01*
G01X430472Y-299959D02*
X429845Y-299854D01*
X429297Y-299434D01*
X428827Y-298804D01*
X428514Y-298069D01*
X428357Y-297229D01*
Y-296389D01*
X428514Y-295549D01*
X428827Y-294814D01*
X429297Y-294184D01*
X429845Y-293764D01*
X430472Y-293659D01*
X431099Y-293764D01*
X431647Y-294184D01*
X432117Y-294814D01*
X432430Y-295549D01*
X432587Y-296389D01*
Y-297229D01*
X432430Y-298069D01*
X432117Y-298804D01*
X431647Y-299434D01*
X431099Y-299854D01*
X430472Y-299959D01*
G01X436772D02*
Y-297124D01*
X435205Y-293659D01*
G01X438339D02*
X436772Y-297124D01*
G01X441349Y-293659D02*
Y-298174D01*
X441662Y-299119D01*
X442289Y-299749D01*
X443072Y-299959D01*
X443855Y-299749D01*
X444482Y-299119D01*
X444795Y-298174D01*
Y-293659D01*
G01X447414Y-299959D02*
X449372Y-293659D01*
X451330Y-299959D01*
G01X450625Y-297754D02*
X448119D01*
G01X453870Y-299959D02*
Y-293659D01*
X457474Y-299959D01*
Y-293659D01*
G01X327870Y-289959D02*
Y-283659D01*
X331474Y-289959D01*
Y-283659D01*
G01X335972Y-289959D02*
X335345Y-289854D01*
X334797Y-289434D01*
X334327Y-288804D01*
X334014Y-288069D01*
X333857Y-287229D01*
Y-286389D01*
X334014Y-285549D01*
X334327Y-284814D01*
X334797Y-284184D01*
X335345Y-283764D01*
X335972Y-283659D01*
X336599Y-283764D01*
X337147Y-284184D01*
X337617Y-284814D01*
X337930Y-285549D01*
X338087Y-286389D01*
Y-287229D01*
X337930Y-288069D01*
X337617Y-288804D01*
X337147Y-289434D01*
X336599Y-289854D01*
X335972Y-289959D01*
G01X342272Y-290169D02*
X342115Y-290064D01*
Y-289854D01*
X342272Y-289749D01*
X342429Y-289854D01*
Y-290064D01*
X342272Y-290169D01*
G01X347084Y-284709D02*
X347554Y-284079D01*
X348102Y-283764D01*
X348729Y-283659D01*
X349512Y-283869D01*
X350060Y-284394D01*
X350217Y-285024D01*
X350139Y-285654D01*
X349825Y-286179D01*
X348259Y-287229D01*
X347554Y-287964D01*
X347084Y-289014D01*
X346927Y-289959D01*
X350217D01*
G01X354872D02*
Y-283659D01*
X353932Y-284919D01*
G01Y-289959D02*
X355812D01*
G01X361172D02*
Y-283659D01*
X360232Y-284919D01*
G01Y-289959D02*
X362112D01*
G01X367315Y-291114D02*
X367629Y-289749D01*
G01X371422Y-283659D02*
X372519Y-289959D01*
X373772Y-283659D01*
X375025Y-289959D01*
X376122Y-283659D01*
G01X381639Y-289959D02*
X378505D01*
Y-283659D01*
X381639D01*
G01X380385Y-286704D02*
X378505D01*
G01X384570Y-289959D02*
Y-283659D01*
X388174Y-289959D01*
Y-283659D01*
G01X391027Y-289959D02*
Y-283659D01*
G01X394317D02*
Y-289959D01*
G01Y-286809D02*
X391027D01*
G01X397249Y-283659D02*
Y-288174D01*
X397562Y-289119D01*
X398189Y-289749D01*
X398972Y-289959D01*
X399755Y-289749D01*
X400382Y-289119D01*
X400695Y-288174D01*
Y-283659D01*
G01X403314Y-289959D02*
X405272Y-283659D01*
X407230Y-289959D01*
G01X406525Y-287754D02*
X404019D01*
G01X416384Y-284709D02*
X416854Y-284079D01*
X417402Y-283764D01*
X418029Y-283659D01*
X418812Y-283869D01*
X419360Y-284394D01*
X419517Y-285024D01*
X419439Y-285654D01*
X419125Y-286179D01*
X417559Y-287229D01*
X416854Y-287964D01*
X416384Y-289014D01*
X416227Y-289959D01*
X419517D01*
G01X422370D02*
Y-283659D01*
X425974Y-289959D01*
Y-283659D01*
G01X428749Y-289959D02*
Y-283659D01*
X430315D01*
X430942Y-283974D01*
X431412Y-284394D01*
X431804Y-285024D01*
X432117Y-285759D01*
X432195Y-286809D01*
X432117Y-287859D01*
X431804Y-288594D01*
X431412Y-289224D01*
X430942Y-289644D01*
X430315Y-289959D01*
X428749D01*
G01X441505D02*
Y-283659D01*
X443464D01*
X444090Y-283974D01*
X444482Y-284394D01*
X444639Y-285234D01*
X444482Y-286074D01*
X444012Y-286599D01*
X443464Y-286914D01*
X441505D01*
G01X443464D02*
X444639Y-289959D01*
G01X447649D02*
Y-283659D01*
X449215D01*
X449842Y-283974D01*
X450312Y-284394D01*
X450704Y-285024D01*
X451017Y-285759D01*
X451095Y-286809D01*
X451017Y-287859D01*
X450704Y-288594D01*
X450312Y-289224D01*
X449842Y-289644D01*
X449215Y-289959D01*
X447649D01*
G01X455672Y-290169D02*
X455515Y-290064D01*
Y-289854D01*
X455672Y-289749D01*
X455829Y-289854D01*
Y-290064D01*
X455672Y-290169D01*
G01X351972Y-279259D02*
X349452Y-278842D01*
X347247Y-277176D01*
X345357Y-274676D01*
X344097Y-271759D01*
X343467Y-268426D01*
Y-265092D01*
X344097Y-261759D01*
X345357Y-258842D01*
X347247Y-256343D01*
X349452Y-254676D01*
X351972Y-254259D01*
X354492Y-254676D01*
X356697Y-256343D01*
X358587Y-258842D01*
X359847Y-261759D01*
X360477Y-265092D01*
Y-268426D01*
X359847Y-271759D01*
X358587Y-274676D01*
X356697Y-277176D01*
X354492Y-278842D01*
X351972Y-279259D01*
G01X354492Y-272592D02*
X358272Y-279259D01*
G01X371817Y-262593D02*
Y-274259D01*
X373077Y-277176D01*
X374967Y-278842D01*
X377172Y-279259D01*
X379377Y-278842D01*
X381267Y-277176D01*
X382527Y-274259D01*
G01Y-279259D02*
Y-262593D01*
G01X408042Y-279259D02*
Y-262593D01*
G01Y-265509D02*
X406782Y-263843D01*
X404892Y-263009D01*
X402687Y-262593D01*
X400482Y-263426D01*
X398592Y-265092D01*
X397332Y-267593D01*
X396702Y-270926D01*
X397332Y-274259D01*
X398592Y-276760D01*
X400482Y-278426D01*
X402687Y-279259D01*
X404892Y-278842D01*
X406782Y-277593D01*
X408042Y-275926D01*
G01X422217Y-279259D02*
Y-262593D01*
G01Y-266759D02*
X423477Y-264676D01*
X425367Y-263009D01*
X427887Y-262593D01*
X430092Y-263009D01*
X431982Y-264676D01*
X432927Y-267593D01*
Y-279259D01*
G01X452772Y-254259D02*
Y-279259D01*
G01X448362Y-262593D02*
X457182D01*
G01X483642Y-279259D02*
Y-262593D01*
G01Y-265509D02*
X482382Y-263843D01*
X480492Y-263009D01*
X478287Y-262593D01*
X476082Y-263426D01*
X474192Y-265092D01*
X472932Y-267593D01*
X472302Y-270926D01*
X472932Y-274259D01*
X474192Y-276760D01*
X476082Y-278426D01*
X478287Y-279259D01*
X480492Y-278842D01*
X482382Y-277593D01*
X483642Y-275926D01*
G01X536722Y-291959D02*
Y-283959D01*
X539322Y-290626D01*
X541922Y-283959D01*
Y-291959D01*
G01X544822D02*
X547322Y-283959D01*
X549822Y-291959D01*
G01X548922Y-289159D02*
X545722D01*
G01X553222Y-290893D02*
X554022Y-291559D01*
X554922Y-291959D01*
X555722D01*
X556522Y-291559D01*
X557122Y-290893D01*
X557422Y-289959D01*
X557222Y-289026D01*
X556722Y-288226D01*
X555822Y-287692D01*
X554622Y-287426D01*
X553922Y-286892D01*
X553622Y-285959D01*
X553822Y-285026D01*
X554322Y-284359D01*
X555022Y-283959D01*
X555722D01*
X556422Y-284226D01*
X557022Y-284892D01*
G01X561122Y-291959D02*
Y-283959D01*
G01X564922D02*
X561122Y-288893D01*
G01X565522Y-291959D02*
X562822Y-286626D01*
G01X570022Y-289292D02*
X572622D01*
G01X579322Y-283959D02*
Y-291959D01*
G01X577022Y-283959D02*
X581622D01*
G01X587322Y-291959D02*
X586522Y-291826D01*
X585822Y-291292D01*
X585222Y-290492D01*
X584822Y-289559D01*
X584622Y-288492D01*
Y-287426D01*
X584822Y-286359D01*
X585222Y-285426D01*
X585822Y-284626D01*
X586522Y-284092D01*
X587322Y-283959D01*
X588122Y-284092D01*
X588822Y-284626D01*
X589422Y-285426D01*
X589822Y-286359D01*
X590022Y-287426D01*
Y-288492D01*
X589822Y-289559D01*
X589422Y-290492D01*
X588822Y-291292D01*
X588122Y-291826D01*
X587322Y-291959D01*
G01X593322D02*
Y-283959D01*
X595722D01*
X596522Y-284359D01*
X597122Y-285292D01*
X597322Y-286359D01*
X597122Y-287426D01*
X596622Y-288226D01*
X595722Y-288626D01*
X593322D01*
G01X523322Y-258959D02*
Y-266959D01*
X527322D01*
G01X535122D02*
Y-261626D01*
G01Y-262559D02*
X534722Y-262026D01*
X534122Y-261759D01*
X533422Y-261626D01*
X532722Y-261892D01*
X532122Y-262426D01*
X531722Y-263226D01*
X531522Y-264292D01*
X531722Y-265359D01*
X532122Y-266159D01*
X532722Y-266692D01*
X533422Y-266959D01*
X534122Y-266826D01*
X534722Y-266426D01*
X535122Y-265893D01*
G01X539222Y-269359D02*
X539822Y-269626D01*
X540622Y-269359D01*
X541122Y-268826D01*
X541522Y-268159D01*
X542122Y-266026D01*
X543422Y-261626D01*
G01X540222D02*
X542122Y-266026D01*
G01X547822Y-263359D02*
X551022D01*
X550722Y-262426D01*
X550222Y-261892D01*
X549522Y-261626D01*
X548822Y-261759D01*
X548222Y-262159D01*
X547822Y-263092D01*
X547622Y-263893D01*
Y-264692D01*
X547822Y-265492D01*
X548322Y-266292D01*
X548922Y-266826D01*
X549622Y-266959D01*
X550322Y-266692D01*
X551022Y-265893D01*
G01X555922Y-266959D02*
Y-261626D01*
G01Y-262692D02*
X556422Y-262159D01*
X556922Y-261759D01*
X557622Y-261626D01*
X558122Y-261759D01*
X558722Y-262159D01*
G01X542022Y-316959D02*
Y-308959D01*
X546622Y-316959D01*
Y-308959D01*
G01X552322Y-311626D02*
Y-316959D01*
G01Y-309492D02*
X552122Y-309359D01*
Y-309092D01*
X552322Y-308959D01*
X552522Y-309092D01*
Y-309359D01*
X552322Y-309492D01*
G01X558622Y-316959D02*
Y-311626D01*
G01Y-312959D02*
X559022Y-312292D01*
X559622Y-311759D01*
X560422Y-311626D01*
X561122Y-311759D01*
X561722Y-312292D01*
X562022Y-313226D01*
Y-316959D01*
G01X570122D02*
Y-311626D01*
G01Y-312559D02*
X569722Y-312026D01*
X569122Y-311759D01*
X568422Y-311626D01*
X567722Y-311892D01*
X567122Y-312426D01*
X566722Y-313226D01*
X566522Y-314292D01*
X566722Y-315359D01*
X567122Y-316159D01*
X567722Y-316692D01*
X568422Y-316959D01*
X569122Y-316826D01*
X569722Y-316426D01*
X570122Y-315893D01*
G01X649922Y-310292D02*
X650522Y-309492D01*
X651222Y-309092D01*
X652022Y-308959D01*
X653022Y-309226D01*
X653722Y-309892D01*
X653922Y-310692D01*
X653822Y-311493D01*
X653422Y-312159D01*
X651422Y-313492D01*
X650522Y-314426D01*
X649922Y-315759D01*
X649722Y-316959D01*
X653922D01*
G01X659822Y-308959D02*
X659022Y-309226D01*
X658422Y-309892D01*
X658022Y-310692D01*
X657722Y-311759D01*
X657622Y-312959D01*
X657722Y-314159D01*
X658022Y-315226D01*
X658422Y-316026D01*
X659022Y-316692D01*
X659822Y-316959D01*
X660622Y-316692D01*
X661222Y-316026D01*
X661622Y-315226D01*
X661922Y-314159D01*
X662022Y-312959D01*
X661922Y-311759D01*
X661622Y-310692D01*
X661222Y-309892D01*
X660622Y-309226D01*
X659822Y-308959D01*
G01X665922Y-310292D02*
X666522Y-309492D01*
X667222Y-309092D01*
X668022Y-308959D01*
X669022Y-309226D01*
X669722Y-309892D01*
X669922Y-310692D01*
X669822Y-311493D01*
X669422Y-312159D01*
X667422Y-313492D01*
X666522Y-314426D01*
X665922Y-315759D01*
X665722Y-316959D01*
X669922D01*
G01X673922Y-310292D02*
X674522Y-309492D01*
X675222Y-309092D01*
X676022Y-308959D01*
X677022Y-309226D01*
X677722Y-309892D01*
X677922Y-310692D01*
X677822Y-311493D01*
X677422Y-312159D01*
X675422Y-313492D01*
X674522Y-314426D01*
X673922Y-315759D01*
X673722Y-316959D01*
X677922D01*
G01X682022Y-317226D02*
X685622Y-308959D01*
G01X691822Y-316959D02*
Y-308959D01*
X690622Y-310559D01*
G01Y-316959D02*
X693022D01*
G01X697922Y-310292D02*
X698522Y-309492D01*
X699222Y-309092D01*
X700022Y-308959D01*
X701022Y-309226D01*
X701722Y-309892D01*
X701922Y-310692D01*
X701822Y-311493D01*
X701422Y-312159D01*
X699422Y-313492D01*
X698522Y-314426D01*
X697922Y-315759D01*
X697722Y-316959D01*
X701922D01*
G01X706022Y-317226D02*
X709622Y-308959D01*
G01X715822D02*
X715022Y-309226D01*
X714422Y-309892D01*
X714022Y-310692D01*
X713722Y-311759D01*
X713622Y-312959D01*
X713722Y-314159D01*
X714022Y-315226D01*
X714422Y-316026D01*
X715022Y-316692D01*
X715822Y-316959D01*
X716622Y-316692D01*
X717222Y-316026D01*
X717622Y-315226D01*
X717922Y-314159D01*
X718022Y-312959D01*
X717922Y-311759D01*
X717622Y-310692D01*
X717222Y-309892D01*
X716622Y-309226D01*
X715822Y-308959D01*
G01X722122Y-316026D02*
X722822Y-316692D01*
X723622Y-316959D01*
X724422Y-316692D01*
X725122Y-315893D01*
X725622Y-314692D01*
X725822Y-313492D01*
Y-312026D01*
X725622Y-310826D01*
X725122Y-309759D01*
X724522Y-309226D01*
X723822Y-308959D01*
X723022Y-309226D01*
X722422Y-309759D01*
X722022Y-310559D01*
X721822Y-311626D01*
X722022Y-312559D01*
X722522Y-313492D01*
X723122Y-314026D01*
X723822Y-314159D01*
X724622Y-313893D01*
X725222Y-313226D01*
X725822Y-312026D01*
G01X649622Y-291959D02*
Y-283959D01*
X651622D01*
X652422Y-284359D01*
X653022Y-284892D01*
X653522Y-285692D01*
X653922Y-286626D01*
X654022Y-287959D01*
X653922Y-289292D01*
X653522Y-290226D01*
X653022Y-291026D01*
X652422Y-291559D01*
X651622Y-291959D01*
X649622D01*
G01X657322D02*
X659822Y-283959D01*
X662322Y-291959D01*
G01X661422Y-289159D02*
X658222D01*
G01X667822Y-283959D02*
X667022Y-284226D01*
X666422Y-284892D01*
X666022Y-285692D01*
X665722Y-286759D01*
X665622Y-287959D01*
X665722Y-289159D01*
X666022Y-290226D01*
X666422Y-291026D01*
X667022Y-291692D01*
X667822Y-291959D01*
X668622Y-291692D01*
X669222Y-291026D01*
X669622Y-290226D01*
X669922Y-289159D01*
X670022Y-287959D01*
X669922Y-286759D01*
X669622Y-285692D01*
X669222Y-284892D01*
X668622Y-284226D01*
X667822Y-283959D01*
G01X673922Y-291959D02*
Y-283959D01*
X677722D01*
G01X676322Y-287826D02*
X673922D01*
G01X683822Y-283959D02*
X683022Y-284226D01*
X682422Y-284892D01*
X682022Y-285692D01*
X681722Y-286759D01*
X681622Y-287959D01*
X681722Y-289159D01*
X682022Y-290226D01*
X682422Y-291026D01*
X683022Y-291692D01*
X683822Y-291959D01*
X684622Y-291692D01*
X685222Y-291026D01*
X685622Y-290226D01*
X685922Y-289159D01*
X686022Y-287959D01*
X685922Y-286759D01*
X685622Y-285692D01*
X685222Y-284892D01*
X684622Y-284226D01*
X683822Y-283959D01*
G01X691822D02*
Y-291959D01*
G01X689522Y-283959D02*
X694122D01*
G01X697922Y-291959D02*
Y-283959D01*
X701722D01*
G01X700322Y-287826D02*
X697922D01*
G01X708622Y-287692D02*
X709022Y-287292D01*
X709322Y-286626D01*
X709522Y-285692D01*
X709322Y-284892D01*
X708922Y-284359D01*
X708222Y-283959D01*
X705522D01*
Y-291959D01*
X708822D01*
X709522Y-291426D01*
X709922Y-290626D01*
X710122Y-289692D01*
X709922Y-288759D01*
X709322Y-287959D01*
X708622Y-287692D01*
X705522D01*
G01X713922Y-288626D02*
X714622Y-287692D01*
X715222Y-287159D01*
X716022Y-286892D01*
X716722Y-287159D01*
X717222Y-287692D01*
X717622Y-288492D01*
X717722Y-289426D01*
X717622Y-290226D01*
X717222Y-291026D01*
X716622Y-291692D01*
X715922Y-291959D01*
X715122Y-291692D01*
X714422Y-290893D01*
X714022Y-289692D01*
X713922Y-288359D01*
X714122Y-286626D01*
X714422Y-285692D01*
X714922Y-284759D01*
X715622Y-284092D01*
X716322Y-283959D01*
X717022Y-284226D01*
X717522Y-284892D01*
G01X721622Y-291959D02*
Y-283959D01*
X723622D01*
X724422Y-284359D01*
X725022Y-284892D01*
X725522Y-285692D01*
X725922Y-286626D01*
X726022Y-287959D01*
X725922Y-289292D01*
X725522Y-290226D01*
X725022Y-291026D01*
X724422Y-291559D01*
X723622Y-291959D01*
X721622D01*
G01X731822Y-283959D02*
X731022Y-284226D01*
X730422Y-284892D01*
X730022Y-285692D01*
X729722Y-286759D01*
X729622Y-287959D01*
X729722Y-289159D01*
X730022Y-290226D01*
X730422Y-291026D01*
X731022Y-291692D01*
X731822Y-291959D01*
X732622Y-291692D01*
X733222Y-291026D01*
X733622Y-290226D01*
X733922Y-289159D01*
X734022Y-287959D01*
X733922Y-286759D01*
X733622Y-285692D01*
X733222Y-284892D01*
X732622Y-284226D01*
X731822Y-283959D01*
G01X649862Y-270000D02*
Y-263700D01*
X652838D01*
G01X651742Y-266745D02*
X649862D01*
G01X657650Y-263700D02*
X657023Y-263910D01*
X656553Y-264435D01*
X656240Y-265065D01*
X656005Y-265905D01*
X655927Y-266850D01*
X656005Y-267795D01*
X656240Y-268635D01*
X656553Y-269265D01*
X657023Y-269790D01*
X657650Y-270000D01*
X658277Y-269790D01*
X658747Y-269265D01*
X659060Y-268635D01*
X659295Y-267795D01*
X659373Y-266850D01*
X659295Y-265905D01*
X659060Y-265065D01*
X658747Y-264435D01*
X658277Y-263910D01*
X657650Y-263700D01*
G01X663950D02*
Y-270000D01*
G01X662148Y-263700D02*
X665752D01*
G01X667900Y-272100D02*
X672600D01*
G01X674983Y-270000D02*
Y-263700D01*
X676863D01*
X677490Y-264015D01*
X677960Y-264750D01*
X678117Y-265590D01*
X677960Y-266430D01*
X677568Y-267060D01*
X676863Y-267375D01*
X674983D01*
G01X684573Y-264225D02*
X684103Y-263910D01*
X683555Y-263700D01*
X682928D01*
X682223Y-264015D01*
X681675Y-264540D01*
X681283Y-265170D01*
X680970Y-266220D01*
X680892Y-267165D01*
X681048Y-268110D01*
X681283Y-268740D01*
X681753Y-269370D01*
X682302Y-269790D01*
X682850Y-270000D01*
X683398D01*
X683947Y-269790D01*
X684417Y-269475D01*
X684808Y-269055D01*
G01X689777Y-266640D02*
X690090Y-266325D01*
X690325Y-265800D01*
X690482Y-265065D01*
X690325Y-264435D01*
X690012Y-264015D01*
X689463Y-263700D01*
X687348D01*
Y-270000D01*
X689933D01*
X690482Y-269580D01*
X690795Y-268950D01*
X690952Y-268215D01*
X690795Y-267480D01*
X690325Y-266850D01*
X689777Y-266640D01*
X687348D01*
G01X693100Y-272100D02*
X697800D01*
G01X700262Y-270000D02*
Y-263700D01*
X703238D01*
G01X702142Y-266745D02*
X700262D01*
G01X706092Y-270000D02*
X708050Y-263700D01*
X710008Y-270000D01*
G01X709303Y-267795D02*
X706797D01*
G01X712548Y-270000D02*
Y-263700D01*
X716152Y-270000D01*
Y-263700D01*
G01X718300Y-272100D02*
X723000D01*
G01X727577Y-266640D02*
X727890Y-266325D01*
X728125Y-265800D01*
X728282Y-265065D01*
X728125Y-264435D01*
X727812Y-264015D01*
X727263Y-263700D01*
X725148D01*
Y-270000D01*
X727733D01*
X728282Y-269580D01*
X728595Y-268950D01*
X728752Y-268215D01*
X728595Y-267480D01*
X728125Y-266850D01*
X727577Y-266640D01*
X725148D01*
G01X733250Y-270000D02*
X732623Y-269895D01*
X732075Y-269475D01*
X731605Y-268845D01*
X731292Y-268110D01*
X731135Y-267270D01*
Y-266430D01*
X731292Y-265590D01*
X731605Y-264855D01*
X732075Y-264225D01*
X732623Y-263805D01*
X733250Y-263700D01*
X733877Y-263805D01*
X734425Y-264225D01*
X734895Y-264855D01*
X735208Y-265590D01*
X735365Y-266430D01*
Y-267270D01*
X735208Y-268110D01*
X734895Y-268845D01*
X734425Y-269475D01*
X733877Y-269895D01*
X733250Y-270000D01*
G01X737592D02*
X739550Y-263700D01*
X741508Y-270000D01*
G01X740803Y-267795D02*
X738297D01*
G01X744283Y-270000D02*
Y-263700D01*
X746242D01*
X746868Y-264015D01*
X747260Y-264435D01*
X747417Y-265275D01*
X747260Y-266115D01*
X746790Y-266640D01*
X746242Y-266955D01*
X744283D01*
G01X746242D02*
X747417Y-270000D01*
G01X750427D02*
Y-263700D01*
X751993D01*
X752620Y-264015D01*
X753090Y-264435D01*
X753482Y-265065D01*
X753795Y-265800D01*
X753873Y-266850D01*
X753795Y-267900D01*
X753482Y-268635D01*
X753090Y-269265D01*
X752620Y-269685D01*
X751993Y-270000D01*
X750427D01*
G01X756100Y-272100D02*
X760800D01*
G01X762713Y-270000D02*
Y-263700D01*
X764750Y-268950D01*
X766787Y-263700D01*
Y-270000D01*
G01X769483D02*
Y-263700D01*
X771363D01*
X771990Y-264015D01*
X772460Y-264750D01*
X772617Y-265590D01*
X772460Y-266430D01*
X772068Y-267060D01*
X771363Y-267375D01*
X769483D01*
G01X775627Y-269055D02*
X776097Y-269580D01*
X776645Y-269895D01*
X777350Y-270000D01*
X778055Y-269790D01*
X778603Y-269370D01*
X778995Y-268635D01*
X779073Y-267795D01*
X778917Y-266955D01*
X778525Y-266430D01*
X777977Y-266010D01*
X777428Y-265905D01*
X776880Y-266010D01*
X776175Y-266430D01*
X776410Y-263700D01*
X778525D01*
G01X783650D02*
X783023Y-263910D01*
X782553Y-264435D01*
X782240Y-265065D01*
X782005Y-265905D01*
X781927Y-266850D01*
X782005Y-267795D01*
X782240Y-268635D01*
X782553Y-269265D01*
X783023Y-269790D01*
X783650Y-270000D01*
X784277Y-269790D01*
X784747Y-269265D01*
X785060Y-268635D01*
X785295Y-267795D01*
X785373Y-266850D01*
X785295Y-265905D01*
X785060Y-265065D01*
X784747Y-264435D01*
X784277Y-263910D01*
X783650Y-263700D01*
G01X790890Y-270000D02*
Y-263700D01*
X787992Y-268215D01*
X791908D01*
G01X796250Y-270000D02*
X796798Y-269895D01*
X797425Y-269580D01*
X797817Y-269055D01*
X797973Y-268320D01*
X797817Y-267585D01*
X797347Y-266955D01*
X796642Y-266640D01*
X795858D01*
X795388Y-266430D01*
X794997Y-265905D01*
X794840Y-265170D01*
X795075Y-264435D01*
X795623Y-263910D01*
X796250Y-263700D01*
X796877Y-263910D01*
X797425Y-264435D01*
X797660Y-265170D01*
X797503Y-265905D01*
X797112Y-266430D01*
X796642Y-266640D01*
X795858D01*
X795153Y-266955D01*
X794683Y-267585D01*
X794527Y-268320D01*
X794683Y-269055D01*
X795075Y-269580D01*
X795702Y-269895D01*
X796250Y-270000D01*
G01X738322Y-319959D02*
Y-311959D01*
X737122Y-313559D01*
G01Y-319959D02*
X739522D01*
G01X744422Y-316626D02*
X745122Y-315692D01*
X745722Y-315159D01*
X746522Y-314892D01*
X747222Y-315159D01*
X747722Y-315692D01*
X748122Y-316492D01*
X748222Y-317426D01*
X748122Y-318226D01*
X747722Y-319026D01*
X747122Y-319692D01*
X746422Y-319959D01*
X745622Y-319692D01*
X744922Y-318893D01*
X744522Y-317692D01*
X744422Y-316359D01*
X744622Y-314626D01*
X744922Y-313692D01*
X745422Y-312759D01*
X746122Y-312092D01*
X746822Y-311959D01*
X747522Y-312226D01*
X748022Y-312892D01*
G01X754322Y-320226D02*
X754122Y-320092D01*
Y-319826D01*
X754322Y-319692D01*
X754522Y-319826D01*
Y-320092D01*
X754322Y-320226D01*
G01X760422Y-316626D02*
X761122Y-315692D01*
X761722Y-315159D01*
X762522Y-314892D01*
X763222Y-315159D01*
X763722Y-315692D01*
X764122Y-316492D01*
X764222Y-317426D01*
X764122Y-318226D01*
X763722Y-319026D01*
X763122Y-319692D01*
X762422Y-319959D01*
X761622Y-319692D01*
X760922Y-318893D01*
X760522Y-317692D01*
X760422Y-316359D01*
X760622Y-314626D01*
X760922Y-313692D01*
X761422Y-312759D01*
X762122Y-312092D01*
X762822Y-311959D01*
X763522Y-312226D01*
X764022Y-312892D01*
G01X783322Y-319959D02*
Y-311959D01*
X782122Y-313559D01*
G01Y-319959D02*
X784522D01*
G01X791122D02*
X791322Y-318226D01*
X791622Y-316759D01*
X792022Y-315426D01*
X792522Y-313959D01*
X793322Y-311959D01*
X789322D01*
G01X799322Y-320226D02*
X799122Y-320092D01*
Y-319826D01*
X799322Y-319692D01*
X799522Y-319826D01*
Y-320092D01*
X799322Y-320226D01*
G01X805422Y-313292D02*
X806022Y-312492D01*
X806722Y-312092D01*
X807522Y-311959D01*
X808522Y-312226D01*
X809222Y-312892D01*
X809422Y-313692D01*
X809322Y-314493D01*
X808922Y-315159D01*
X806922Y-316492D01*
X806022Y-317426D01*
X805422Y-318759D01*
X805222Y-319959D01*
X809422D01*
G01X803122Y-294959D02*
Y-286959D01*
X805122D01*
X805922Y-287359D01*
X806522Y-287892D01*
X807022Y-288692D01*
X807422Y-289626D01*
X807522Y-290959D01*
X807422Y-292292D01*
X807022Y-293226D01*
X806522Y-294026D01*
X805922Y-294559D01*
X805122Y-294959D01*
X803122D01*
G54D36*
X56243Y63842D03*
Y408878D03*
Y463878D03*
Y772264D03*
Y827264D03*
Y1136150D03*
Y1190650D03*
X64843Y63842D03*
X56743Y120342D03*
X65343D03*
X64843Y408878D03*
Y463878D03*
Y772264D03*
Y827264D03*
Y1136150D03*
Y1190650D03*
X146800Y64000D03*
X138200D03*
X147300Y119342D03*
X138700D03*
X147300Y407228D03*
X138700D03*
X147300Y463000D03*
X138700D03*
X146800Y773114D03*
X138200D03*
X147300Y826614D03*
X138700D03*
X147300Y1135000D03*
X138700D03*
X147300Y1190000D03*
X138700D03*
G54D45*
X56000Y1197327D03*
Y1200673D03*
X148500Y58173D03*
Y54827D03*
G54D27*
X25429Y511579D03*
Y513547D03*
Y515516D03*
Y517484D03*
Y519453D03*
Y521421D03*
X41571D03*
Y519453D03*
Y517484D03*
Y515516D03*
Y513547D03*
Y511579D03*
X164929Y513079D03*
Y522921D03*
Y520953D03*
Y518984D03*
Y517016D03*
Y515047D03*
X181071Y513079D03*
Y515047D03*
Y517016D03*
Y518984D03*
Y520953D03*
Y522921D03*
G54D18*
X26378Y48858D03*
Y412244D03*
Y775630D03*
Y1139016D03*
X177165Y103976D03*
Y467362D03*
Y830748D03*
Y1194134D03*
G54D28*
X33500Y516500D03*
X173000Y518000D03*
G54D37*
X55327Y97500D03*
Y113692D03*
X54827Y443728D03*
Y457228D03*
X55327Y778500D03*
X54827Y810000D03*
Y820614D03*
Y1173500D03*
Y1184000D03*
X71870Y56342D03*
X75216D03*
X71827Y75192D03*
X75173D03*
X58870Y70342D03*
X62216D03*
X58673Y97500D03*
X59370Y126842D03*
X62716D03*
X58673Y113692D03*
X71870Y401378D03*
X75216D03*
X58870Y415378D03*
X62216D03*
X71827Y420228D03*
X75173D03*
X58173Y443728D03*
Y457228D03*
X58870Y470378D03*
X62216D03*
X58673Y778500D03*
X71870Y764764D03*
X75216D03*
X71827Y783614D03*
X75173D03*
X58173Y810000D03*
Y820614D03*
X58870Y833764D03*
X62216D03*
X58870Y1142650D03*
X62216D03*
X71870Y1128650D03*
X75216D03*
X71827Y1147500D03*
X75173D03*
X58173Y1173500D03*
Y1184000D03*
X145327Y79842D03*
Y94000D03*
X131173Y107728D03*
X127827D03*
X144673Y112842D03*
X141327D03*
X133673Y124500D03*
X130327D03*
X144673Y400728D03*
X141327D03*
X145327Y428000D03*
Y413728D03*
X144673Y456728D03*
X141327D03*
X131173Y451614D03*
X127827D03*
X131673Y470728D03*
X128327D03*
X148173Y766500D03*
X144827D03*
X148173Y801500D03*
X144827D03*
X145327Y791500D03*
X144673Y820114D03*
X141327D03*
X131173Y815000D03*
X127827D03*
X132173Y834500D03*
X128827D03*
X145327Y1141500D03*
X144673Y1128500D03*
X141327D03*
X145327Y1151000D03*
Y1183500D03*
X131673Y1178500D03*
X128327D03*
X131173Y1198000D03*
X127827D03*
X148673Y79842D03*
Y94000D03*
Y428000D03*
Y413728D03*
Y791500D03*
Y1141500D03*
Y1151000D03*
Y1183500D03*
G54D19*
X14700Y144531D03*
Y137531D03*
X23400Y383500D03*
X14600Y379500D03*
Y387500D03*
X18600Y867000D03*
Y860000D03*
X55600Y850500D03*
X71600Y137500D03*
X64400Y846500D03*
Y854500D03*
X80400Y133500D03*
Y141500D03*
X122100Y131000D03*
Y139000D03*
X130900Y135000D03*
X189054Y145631D03*
Y138631D03*
X194900Y388000D03*
X186100Y384000D03*
Y392000D03*
X192000Y867500D03*
X194400Y856000D03*
X185600Y852000D03*
Y860000D03*
X192000Y874500D03*
G54D46*
X82992Y17126D03*
X87992D03*
X92992D03*
X97992D03*
G54D29*
X27000Y531016D03*
X19000D03*
X23000D03*
X17000Y989516D03*
X33000Y531016D03*
X64543Y54858D03*
X77000Y87016D03*
Y104516D03*
X66561Y279244D03*
X77000Y432516D03*
Y450016D03*
X76500Y526016D03*
X71000Y534016D03*
X76500D03*
X68000Y565016D03*
X75000D03*
X78500Y608516D03*
X72000Y628516D03*
X68000D03*
X77000Y800516D03*
Y813516D03*
X67061Y1006016D03*
X76500Y1157516D03*
Y1173516D03*
X96000Y53216D03*
X91500D03*
Y109516D03*
Y467516D03*
X82000Y526016D03*
X93000Y534016D03*
X87500D03*
X82000D03*
X101000Y556016D03*
X91000D03*
X95500D03*
X80000D03*
X93000Y565016D03*
X101000D03*
X85000D03*
X80800Y640016D03*
X80900Y628516D03*
X91500Y830516D03*
Y1193516D03*
X106500Y53216D03*
X102500D03*
X103000Y130016D03*
X113500Y400516D03*
X115000Y420516D03*
X106500Y500516D03*
X113500Y487516D03*
X119000D03*
X116000Y524016D03*
X106000Y531516D03*
X110000D03*
X114500Y556016D03*
X124500Y555016D03*
X107500Y556016D03*
X124500Y565016D03*
X107500D03*
X117000D03*
X117500Y765516D03*
X114500Y785516D03*
X115500Y1148516D03*
X118500Y1128516D03*
X143500Y55016D03*
X135500Y487516D03*
X131500Y555016D03*
X135500D03*
Y565016D03*
X131500D03*
X129000Y1129016D03*
X166500Y532016D03*
Y539016D03*
X161000Y854516D03*
X175858Y279244D03*
X171500Y532016D03*
Y539016D03*
X176500Y532016D03*
X175858Y1006016D03*
G54D38*
X50150Y385441D03*
X43850Y388000D03*
X50150Y390559D03*
X71650Y86441D03*
X65350Y106000D03*
X71650Y108559D03*
Y103441D03*
X65350Y89000D03*
X71650Y91559D03*
Y432441D03*
X65350Y451500D03*
X71650Y454059D03*
Y448941D03*
X65350Y435000D03*
X71650Y437559D03*
X65350Y799500D03*
X71650Y802059D03*
Y796941D03*
X65350Y815500D03*
X71650Y818059D03*
Y812941D03*
X71150Y1173441D03*
X64850Y1160000D03*
X71150Y1162559D03*
Y1157441D03*
X64850Y1176000D03*
X71150Y1178559D03*
X88350Y123500D03*
X94650Y126059D03*
Y120941D03*
X80850Y848500D03*
X87150Y845941D03*
Y851059D03*
X114650Y131500D03*
X108350Y128941D03*
Y134059D03*
X138650Y73000D03*
X132350Y70441D03*
Y75559D03*
Y86441D03*
X138650Y89000D03*
X132350Y91559D03*
X139150Y416500D03*
X132850Y413941D03*
Y419059D03*
X139150Y432500D03*
X132850Y429941D03*
Y435059D03*
X133350Y780141D03*
X139650Y782700D03*
X133350Y785259D03*
X138650Y798500D03*
X132350Y795941D03*
Y801059D03*
X138650Y1146000D03*
X132350Y1143441D03*
Y1148559D03*
X138650Y1162000D03*
X132350Y1159441D03*
Y1164559D03*
X153850Y386441D03*
X160150Y389000D03*
X153850Y391559D03*
X166850Y853441D03*
Y858559D03*
X173150Y856000D03*
G54D47*
X99260Y71441D03*
Y76559D03*
X97260Y101000D03*
X96260Y408441D03*
Y413559D03*
X99760Y460000D03*
X95760Y773441D03*
Y778559D03*
X97760Y822000D03*
Y1136941D03*
Y1142059D03*
Y1185000D03*
X106740Y74000D03*
X104740Y103559D03*
Y98441D03*
X103740Y411000D03*
X107240Y462559D03*
Y457441D03*
X103240Y776000D03*
X105240Y824559D03*
Y819441D03*
Y1139500D03*
Y1187559D03*
Y1182441D03*
G54D39*
X37000Y384600D03*
Y390400D03*
X72000Y463100D03*
Y468900D03*
X82300Y121100D03*
Y126900D03*
X122500Y105100D03*
Y110900D03*
X185000Y868100D03*
Y873900D03*
G54D48*
X85941Y104740D03*
X91059D03*
Y97260D03*
X88500D03*
X85941D03*
X91059Y455260D03*
X88500D03*
X85941D03*
Y462740D03*
X91059D03*
X85941Y825740D03*
X91059D03*
Y818260D03*
X88500D03*
X85941D03*
Y1188740D03*
X91059D03*
Y1181260D03*
X88500D03*
X85941D03*
X118559Y71260D03*
X113441D03*
Y78740D03*
X116000D03*
X118559D03*
X117559Y408260D03*
X112441D03*
Y415740D03*
X115000D03*
X117559D03*
X117059Y773260D03*
X111941D03*
Y780740D03*
X114500D03*
X117059D03*
X118059Y1136260D03*
X112941D03*
Y1143740D03*
X115500D03*
X118059D03*
G54D49*
X95500Y388000D03*
X158000Y17500D03*
X166960Y1304230D03*
M02*
